(kicad_sch
	(version 20231120)
	(generator "eeschema")
	(generator_version "8.0")
	(paper "A3" portrait)
	(title_block
		(title "Thunderbolt GPU Adapter")
		(date "2024-07-09")
		(rev "1.3.0")
		(company "Antmicro Ltd")
		(comment 1 "www.antmicro.com")
	)
	(junction
		(at 185.42 203.2)
		(diameter 0)
		(color 0 0 0 0)
	)
	(junction
		(at 72.39 67.31)
		(diameter 0)
		(color 0 0 0 0)
	)
	(junction
		(at 27.94 77.47)
		(diameter 0)
		(color 0 0 0 0)
	)
	(junction
		(at 62.23 110.49)
		(diameter 0)
		(color 0 0 0 0)
	)
	(junction
		(at 255.27 118.11)
		(diameter 0)
		(color 0 0 0 0)
	)
	(junction
		(at 46.99 58.42)
		(diameter 0)
		(color 0 0 0 0)
	)
	(junction
		(at 173.99 46.99)
		(diameter 0)
		(color 0 0 0 0)
	)
	(junction
		(at 130.81 198.12)
		(diameter 0)
		(color 0 0 0 0)
	)
	(junction
		(at 160.02 354.33)
		(diameter 0)
		(color 0 0 0 0)
	)
	(junction
		(at 45.72 198.12)
		(diameter 0)
		(color 0 0 0 0)
	)
	(junction
		(at 181.61 346.71)
		(diameter 0)
		(color 0 0 0 0)
	)
	(junction
		(at 133.35 116.84)
		(diameter 0)
		(color 0 0 0 0)
	)
	(junction
		(at 157.48 251.46)
		(diameter 0)
		(color 0 0 0 0)
	)
	(junction
		(at 168.91 228.6)
		(diameter 0)
		(color 0 0 0 0)
	)
	(junction
		(at 220.98 203.2)
		(diameter 0)
		(color 0 0 0 0)
	)
	(junction
		(at 153.67 46.99)
		(diameter 0)
		(color 0 0 0 0)
	)
	(junction
		(at 57.15 330.2)
		(diameter 0)
		(color 0 0 0 0)
	)
	(junction
		(at 237.49 346.71)
		(diameter 0)
		(color 0 0 0 0)
	)
	(junction
		(at 214.63 113.03)
		(diameter 0)
		(color 0 0 0 0)
	)
	(junction
		(at 255.27 300.99)
		(diameter 0)
		(color 0 0 0 0)
	)
	(junction
		(at 120.65 359.41)
		(diameter 0)
		(color 0 0 0 0)
	)
	(junction
		(at 66.04 198.12)
		(diameter 0)
		(color 0 0 0 0)
	)
	(junction
		(at 133.35 118.11)
		(diameter 0)
		(color 0 0 0 0)
	)
	(junction
		(at 55.88 198.12)
		(diameter 0)
		(color 0 0 0 0)
	)
	(junction
		(at 151.13 354.33)
		(diameter 0)
		(color 0 0 0 0)
	)
	(junction
		(at 46.99 260.35)
		(diameter 0)
		(color 0 0 0 0)
	)
	(junction
		(at 130.81 346.71)
		(diameter 0)
		(color 0 0 0 0)
	)
	(junction
		(at 40.64 72.39)
		(diameter 0)
		(color 0 0 0 0)
	)
	(junction
		(at 60.96 82.55)
		(diameter 0)
		(color 0 0 0 0)
	)
	(junction
		(at 217.17 129.54)
		(diameter 0)
		(color 0 0 0 0)
	)
	(junction
		(at 232.41 262.89)
		(diameter 0)
		(color 0 0 0 0)
	)
	(junction
		(at 57.15 242.57)
		(diameter 0)
		(color 0 0 0 0)
	)
	(junction
		(at 76.2 198.12)
		(diameter 0)
		(color 0 0 0 0)
	)
	(junction
		(at 250.19 316.23)
		(diameter 0)
		(color 0 0 0 0)
	)
	(junction
		(at 74.93 330.2)
		(diameter 0)
		(color 0 0 0 0)
	)
	(junction
		(at 240.03 203.2)
		(diameter 0)
		(color 0 0 0 0)
	)
	(junction
		(at 46.99 153.67)
		(diameter 0)
		(color 0 0 0 0)
	)
	(junction
		(at 146.05 125.73)
		(diameter 0)
		(color 0 0 0 0)
	)
	(junction
		(at 172.72 205.74)
		(diameter 0)
		(color 0 0 0 0)
	)
	(junction
		(at 154.94 77.47)
		(diameter 0)
		(color 0 0 0 0)
	)
	(junction
		(at 60.96 46.99)
		(diameter 0)
		(color 0 0 0 0)
	)
	(junction
		(at 133.35 115.57)
		(diameter 0)
		(color 0 0 0 0)
	)
	(junction
		(at 72.39 138.43)
		(diameter 0)
		(color 0 0 0 0)
	)
	(junction
		(at 74.93 349.25)
		(diameter 0)
		(color 0 0 0 0)
	)
	(junction
		(at 99.06 361.95)
		(diameter 0)
		(color 0 0 0 0)
	)
	(junction
		(at 182.88 46.99)
		(diameter 0)
		(color 0 0 0 0)
	)
	(junction
		(at 262.89 203.2)
		(diameter 0)
		(color 0 0 0 0)
	)
	(junction
		(at 96.52 198.12)
		(diameter 0)
		(color 0 0 0 0)
	)
	(junction
		(at 115.57 238.76)
		(diameter 0)
		(color 0 0 0 0)
	)
	(junction
		(at 223.52 300.99)
		(diameter 0)
		(color 0 0 0 0)
	)
	(junction
		(at 60.96 67.31)
		(diameter 0)
		(color 0 0 0 0)
	)
	(junction
		(at 199.39 346.71)
		(diameter 0)
		(color 0 0 0 0)
	)
	(junction
		(at 128.27 210.82)
		(diameter 0)
		(color 0 0 0 0)
	)
	(junction
		(at 91.44 384.81)
		(diameter 0)
		(color 0 0 0 0)
	)
	(junction
		(at 203.2 203.2)
		(diameter 0)
		(color 0 0 0 0)
	)
	(junction
		(at 247.65 74.93)
		(diameter 0)
		(color 0 0 0 0)
	)
	(junction
		(at 83.82 384.81)
		(diameter 0)
		(color 0 0 0 0)
	)
	(junction
		(at 237.49 80.01)
		(diameter 0)
		(color 0 0 0 0)
	)
	(junction
		(at 50.8 156.21)
		(diameter 0)
		(color 0 0 0 0)
	)
	(junction
		(at 72.39 62.23)
		(diameter 0)
		(color 0 0 0 0)
	)
	(junction
		(at 128.27 218.44)
		(diameter 0)
		(color 0 0 0 0)
	)
	(junction
		(at 160.02 138.43)
		(diameter 0)
		(color 0 0 0 0)
	)
	(junction
		(at 86.36 198.12)
		(diameter 0)
		(color 0 0 0 0)
	)
	(junction
		(at 162.56 77.47)
		(diameter 0)
		(color 0 0 0 0)
	)
	(junction
		(at 34.29 60.96)
		(diameter 0)
		(color 0 0 0 0)
	)
	(junction
		(at 190.5 346.71)
		(diameter 0)
		(color 0 0 0 0)
	)
	(junction
		(at 46.99 384.81)
		(diameter 0)
		(color 0 0 0 0)
	)
	(junction
		(at 36.83 330.2)
		(diameter 0)
		(color 0 0 0 0)
	)
	(junction
		(at 92.71 330.2)
		(diameter 0)
		(color 0 0 0 0)
	)
	(junction
		(at 224.79 262.89)
		(diameter 0)
		(color 0 0 0 0)
	)
	(junction
		(at 256.54 262.89)
		(diameter 0)
		(color 0 0 0 0)
	)
	(junction
		(at 231.14 80.01)
		(diameter 0)
		(color 0 0 0 0)
	)
	(junction
		(at 213.36 262.89)
		(diameter 0)
		(color 0 0 0 0)
	)
	(junction
		(at 133.35 85.09)
		(diameter 0)
		(color 0 0 0 0)
	)
	(junction
		(at 265.43 300.99)
		(diameter 0)
		(color 0 0 0 0)
	)
	(junction
		(at 27.94 60.96)
		(diameter 0)
		(color 0 0 0 0)
	)
	(junction
		(at 231.14 300.99)
		(diameter 0)
		(color 0 0 0 0)
	)
	(junction
		(at 60.96 85.09)
		(diameter 0)
		(color 0 0 0 0)
	)
	(junction
		(at 34.29 74.93)
		(diameter 0)
		(color 0 0 0 0)
	)
	(junction
		(at 128.27 208.28)
		(diameter 0)
		(color 0 0 0 0)
	)
	(junction
		(at 160.02 346.71)
		(diameter 0)
		(color 0 0 0 0)
	)
	(junction
		(at 251.46 278.13)
		(diameter 0)
		(color 0 0 0 0)
	)
	(junction
		(at 250.19 203.2)
		(diameter 0)
		(color 0 0 0 0)
	)
	(junction
		(at 27.94 330.2)
		(diameter 0)
		(color 0 0 0 0)
	)
	(junction
		(at 233.68 218.44)
		(diameter 0)
		(color 0 0 0 0)
	)
	(junction
		(at 64.77 330.2)
		(diameter 0)
		(color 0 0 0 0)
	)
	(junction
		(at 194.31 203.2)
		(diameter 0)
		(color 0 0 0 0)
	)
	(junction
		(at 72.39 52.07)
		(diameter 0)
		(color 0 0 0 0)
	)
	(junction
		(at 168.91 236.22)
		(diameter 0)
		(color 0 0 0 0)
	)
	(junction
		(at 172.72 74.93)
		(diameter 0)
		(color 0 0 0 0)
	)
	(junction
		(at 212.09 203.2)
		(diameter 0)
		(color 0 0 0 0)
	)
	(junction
		(at 81.28 349.25)
		(diameter 0)
		(color 0 0 0 0)
	)
	(junction
		(at 256.54 203.2)
		(diameter 0)
		(color 0 0 0 0)
	)
	(junction
		(at 181.61 74.93)
		(diameter 0)
		(color 0 0 0 0)
	)
	(junction
		(at 158.75 205.74)
		(diameter 0)
		(color 0 0 0 0)
	)
	(junction
		(at 114.3 384.81)
		(diameter 0)
		(color 0 0 0 0)
	)
	(junction
		(at 29.21 198.12)
		(diameter 0)
		(color 0 0 0 0)
	)
	(junction
		(at 196.85 113.03)
		(diameter 0)
		(color 0 0 0 0)
	)
	(junction
		(at 83.82 330.2)
		(diameter 0)
		(color 0 0 0 0)
	)
	(junction
		(at 220.98 346.71)
		(diameter 0)
		(color 0 0 0 0)
	)
	(junction
		(at 151.13 346.71)
		(diameter 0)
		(color 0 0 0 0)
	)
	(junction
		(at 115.57 236.22)
		(diameter 0)
		(color 0 0 0 0)
	)
	(junction
		(at 266.7 203.2)
		(diameter 0)
		(color 0 0 0 0)
	)
	(junction
		(at 172.72 346.71)
		(diameter 0)
		(color 0 0 0 0)
	)
	(junction
		(at 123.19 251.46)
		(diameter 0)
		(color 0 0 0 0)
	)
	(junction
		(at 43.18 102.87)
		(diameter 0)
		(color 0 0 0 0)
	)
	(junction
		(at 123.19 241.3)
		(diameter 0)
		(color 0 0 0 0)
	)
	(junction
		(at 96.52 205.74)
		(diameter 0)
		(color 0 0 0 0)
	)
	(junction
		(at 229.87 346.71)
		(diameter 0)
		(color 0 0 0 0)
	)
	(junction
		(at 60.96 52.07)
		(diameter 0)
		(color 0 0 0 0)
	)
	(junction
		(at 54.61 58.42)
		(diameter 0)
		(color 0 0 0 0)
	)
	(junction
		(at 182.88 203.2)
		(diameter 0)
		(color 0 0 0 0)
	)
	(junction
		(at 163.83 46.99)
		(diameter 0)
		(color 0 0 0 0)
	)
	(junction
		(at 264.16 118.11)
		(diameter 0)
		(color 0 0 0 0)
	)
	(junction
		(at 234.95 62.23)
		(diameter 0)
		(color 0 0 0 0)
	)
	(junction
		(at 233.68 203.2)
		(diameter 0)
		(color 0 0 0 0)
	)
	(junction
		(at 115.57 218.44)
		(diameter 0)
		(color 0 0 0 0)
	)
	(junction
		(at 204.47 113.03)
		(diameter 0)
		(color 0 0 0 0)
	)
	(junction
		(at 60.96 87.63)
		(diameter 0)
		(color 0 0 0 0)
	)
	(no_connect
		(at 73.66 97.79)
	)
	(no_connect
		(at 73.66 41.91)
	)
	(no_connect
		(at 73.66 113.03)
	)
	(no_connect
		(at 132.08 39.37)
	)
	(no_connect
		(at 73.66 100.33)
	)
	(no_connect
		(at 73.66 105.41)
	)
	(no_connect
		(at 132.08 41.91)
	)
	(no_connect
		(at 73.66 130.81)
	)
	(no_connect
		(at 73.66 95.25)
	)
	(no_connect
		(at 73.66 133.35)
	)
	(no_connect
		(at 73.66 39.37)
	)
	(wire
		(pts
			(xy 199.39 346.71) (xy 209.55 346.71)
		)
		(stroke
			(width 0)
			(type default)
		)
	)
	(wire
		(pts
			(xy 69.85 85.09) (xy 73.66 85.09)
		)
		(stroke
			(width 0)
			(type default)
		)
	)
	(wire
		(pts
			(xy 156.21 248.92) (xy 157.48 248.92)
		)
		(stroke
			(width 0)
			(type default)
		)
	)
	(wire
		(pts
			(xy 168.91 233.68) (xy 156.21 233.68)
		)
		(stroke
			(width 0)
			(type default)
		)
	)
	(wire
		(pts
			(xy 255.27 121.92) (xy 255.27 118.11)
		)
		(stroke
			(width 0)
			(type default)
		)
	)
	(wire
		(pts
			(xy 140.97 148.59) (xy 148.59 148.59)
		)
		(stroke
			(width 0)
			(type default)
		)
	)
	(wire
		(pts
			(xy 128.27 217.17) (xy 128.27 218.44)
		)
		(stroke
			(width 0)
			(type default)
		)
	)
	(wire
		(pts
			(xy 55.88 198.12) (xy 66.04 198.12)
		)
		(stroke
			(width 0)
			(type default)
		)
	)
	(wire
		(pts
			(xy 223.52 300.99) (xy 223.52 309.88)
		)
		(stroke
			(width 0)
			(type default)
		)
	)
	(wire
		(pts
			(xy 133.35 85.09) (xy 137.16 85.09)
		)
		(stroke
			(width 0)
			(type default)
		)
	)
	(wire
		(pts
			(xy 40.64 72.39) (xy 73.66 72.39)
		)
		(stroke
			(width 0)
			(type default)
		)
	)
	(wire
		(pts
			(xy 167.64 245.11) (xy 167.64 243.84)
		)
		(stroke
			(width 0)
			(type default)
		)
	)
	(wire
		(pts
			(xy 266.7 201.93) (xy 266.7 203.2)
		)
		(stroke
			(width 0)
			(type default)
		)
	)
	(wire
		(pts
			(xy 132.08 115.57) (xy 133.35 115.57)
		)
		(stroke
			(width 0)
			(type default)
		)
	)
	(wire
		(pts
			(xy 132.08 138.43) (xy 160.02 138.43)
		)
		(stroke
			(width 0)
			(type default)
		)
	)
	(wire
		(pts
			(xy 246.38 120.65) (xy 240.03 120.65)
		)
		(stroke
			(width 0)
			(type default)
		)
	)
	(wire
		(pts
			(xy 91.44 392.43) (xy 91.44 394.97)
		)
		(stroke
			(width 0)
			(type default)
		)
	)
	(wire
		(pts
			(xy 237.49 80.01) (xy 241.3 80.01)
		)
		(stroke
			(width 0)
			(type default)
		)
	)
	(wire
		(pts
			(xy 214.63 119.38) (xy 214.63 120.65)
		)
		(stroke
			(width 0)
			(type default)
		)
	)
	(wire
		(pts
			(xy 43.18 58.42) (xy 46.99 58.42)
		)
		(stroke
			(width 0)
			(type default)
		)
	)
	(wire
		(pts
			(xy 132.08 74.93) (xy 172.72 74.93)
		)
		(stroke
			(width 0)
			(type default)
		)
	)
	(wire
		(pts
			(xy 160.02 361.95) (xy 160.02 364.49)
		)
		(stroke
			(width 0)
			(type default)
		)
	)
	(wire
		(pts
			(xy 223.52 314.96) (xy 223.52 320.04)
		)
		(stroke
			(width 0)
			(type default)
		)
	)
	(wire
		(pts
			(xy 158.75 205.74) (xy 172.72 205.74)
		)
		(stroke
			(width 0)
			(type default)
		)
	)
	(wire
		(pts
			(xy 214.63 113.03) (xy 214.63 114.3)
		)
		(stroke
			(width 0)
			(type default)
		)
	)
	(wire
		(pts
			(xy 26.67 74.93) (xy 34.29 74.93)
		)
		(stroke
			(width 0)
			(type default)
		)
	)
	(wire
		(pts
			(xy 132.08 113.03) (xy 133.35 113.03)
		)
		(stroke
			(width 0)
			(type default)
		)
	)
	(wire
		(pts
			(xy 60.96 85.09) (xy 64.77 85.09)
		)
		(stroke
			(width 0)
			(type default)
		)
	)
	(wire
		(pts
			(xy 123.19 251.46) (xy 123.19 252.73)
		)
		(stroke
			(width 0)
			(type default)
		)
	)
	(wire
		(pts
			(xy 181.61 74.93) (xy 184.15 74.93)
		)
		(stroke
			(width 0)
			(type default)
		)
	)
	(wire
		(pts
			(xy 69.85 102.87) (xy 73.66 102.87)
		)
		(stroke
			(width 0)
			(type default)
		)
	)
	(wire
		(pts
			(xy 132.08 153.67) (xy 135.89 153.67)
		)
		(stroke
			(width 0)
			(type default)
		)
	)
	(wire
		(pts
			(xy 199.39 363.22) (xy 199.39 364.49)
		)
		(stroke
			(width 0)
			(type default)
		)
	)
	(wire
		(pts
			(xy 40.64 60.96) (xy 40.64 63.5)
		)
		(stroke
			(width 0)
			(type default)
		)
	)
	(wire
		(pts
			(xy 123.19 243.84) (xy 123.19 241.3)
		)
		(stroke
			(width 0)
			(type default)
		)
	)
	(wire
		(pts
			(xy 256.54 262.89) (xy 257.81 262.89)
		)
		(stroke
			(width 0)
			(type default)
		)
	)
	(wire
		(pts
			(xy 132.08 59.69) (xy 133.35 59.69)
		)
		(stroke
			(width 0)
			(type default)
		)
	)
	(wire
		(pts
			(xy 60.96 53.34) (xy 60.96 52.07)
		)
		(stroke
			(width 0)
			(type default)
		)
	)
	(wire
		(pts
			(xy 190.5 345.44) (xy 190.5 346.71)
		)
		(stroke
			(width 0)
			(type default)
		)
	)
	(wire
		(pts
			(xy 111.76 236.22) (xy 115.57 236.22)
		)
		(stroke
			(width 0)
			(type default)
		)
	)
	(wire
		(pts
			(xy 72.39 62.23) (xy 72.39 67.31)
		)
		(stroke
			(width 0)
			(type default)
		)
	)
	(wire
		(pts
			(xy 132.08 49.53) (xy 133.35 49.53)
		)
		(stroke
			(width 0)
			(type default)
		)
	)
	(wire
		(pts
			(xy 111.76 245.11) (xy 111.76 243.84)
		)
		(stroke
			(width 0)
			(type default)
		)
	)
	(wire
		(pts
			(xy 156.21 236.22) (xy 162.56 236.22)
		)
		(stroke
			(width 0)
			(type default)
		)
	)
	(wire
		(pts
			(xy 81.28 349.25) (xy 81.28 351.79)
		)
		(stroke
			(width 0)
			(type default)
		)
	)
	(wire
		(pts
			(xy 101.6 351.79) (xy 93.98 351.79)
		)
		(stroke
			(width 0)
			(type default)
		)
	)
	(wire
		(pts
			(xy 62.23 123.19) (xy 73.66 123.19)
		)
		(stroke
			(width 0)
			(type default)
		)
	)
	(wire
		(pts
			(xy 138.43 64.77) (xy 148.59 64.77)
		)
		(stroke
			(width 0)
			(type default)
		)
	)
	(wire
		(pts
			(xy 256.54 62.23) (xy 261.62 62.23)
		)
		(stroke
			(width 0)
			(type default)
		)
	)
	(wire
		(pts
			(xy 224.79 220.98) (xy 224.79 232.41)
		)
		(stroke
			(width 0)
			(type default)
		)
	)
	(wire
		(pts
			(xy 232.41 278.13) (xy 233.68 278.13)
		)
		(stroke
			(width 0)
			(type default)
		)
	)
	(wire
		(pts
			(xy 62.23 125.73) (xy 73.66 125.73)
		)
		(stroke
			(width 0)
			(type default)
		)
	)
	(wire
		(pts
			(xy 172.72 74.93) (xy 172.72 82.55)
		)
		(stroke
			(width 0)
			(type default)
		)
	)
	(wire
		(pts
			(xy 74.93 349.25) (xy 74.93 351.79)
		)
		(stroke
			(width 0)
			(type default)
		)
	)
	(wire
		(pts
			(xy 156.21 218.44) (xy 233.68 218.44)
		)
		(stroke
			(width 0)
			(type default)
		)
	)
	(wire
		(pts
			(xy 190.5 346.71) (xy 190.5 353.06)
		)
		(stroke
			(width 0)
			(type default)
		)
	)
	(wire
		(pts
			(xy 83.82 337.82) (xy 83.82 340.36)
		)
		(stroke
			(width 0)
			(type default)
		)
	)
	(wire
		(pts
			(xy 250.19 205.74) (xy 250.19 203.2)
		)
		(stroke
			(width 0)
			(type default)
		)
	)
	(wire
		(pts
			(xy 214.63 113.03) (xy 222.25 113.03)
		)
		(stroke
			(width 0)
			(type default)
		)
	)
	(wire
		(pts
			(xy 140.97 158.75) (xy 148.59 158.75)
		)
		(stroke
			(width 0)
			(type default)
		)
	)
	(wire
		(pts
			(xy 163.83 46.99) (xy 163.83 50.8)
		)
		(stroke
			(width 0)
			(type default)
		)
	)
	(wire
		(pts
			(xy 132.08 133.35) (xy 135.89 133.35)
		)
		(stroke
			(width 0)
			(type default)
		)
	)
	(wire
		(pts
			(xy 266.7 203.2) (xy 270.51 203.2)
		)
		(stroke
			(width 0)
			(type default)
		)
	)
	(wire
		(pts
			(xy 163.83 55.88) (xy 163.83 58.42)
		)
		(stroke
			(width 0)
			(type default)
		)
	)
	(wire
		(pts
			(xy 71.12 163.83) (xy 73.66 163.83)
		)
		(stroke
			(width 0)
			(type default)
		)
	)
	(wire
		(pts
			(xy 233.68 217.17) (xy 233.68 218.44)
		)
		(stroke
			(width 0)
			(type default)
		)
	)
	(wire
		(pts
			(xy 255.27 300.99) (xy 255.27 313.69)
		)
		(stroke
			(width 0)
			(type default)
		)
	)
	(wire
		(pts
			(xy 167.64 243.84) (xy 156.21 243.84)
		)
		(stroke
			(width 0)
			(type default)
		)
	)
	(wire
		(pts
			(xy 227.33 80.01) (xy 231.14 80.01)
		)
		(stroke
			(width 0)
			(type default)
		)
	)
	(wire
		(pts
			(xy 255.27 300.99) (xy 256.54 300.99)
		)
		(stroke
			(width 0)
			(type default)
		)
	)
	(wire
		(pts
			(xy 232.41 275.59) (xy 233.68 275.59)
		)
		(stroke
			(width 0)
			(type default)
		)
	)
	(wire
		(pts
			(xy 193.04 46.99) (xy 196.85 46.99)
		)
		(stroke
			(width 0)
			(type default)
		)
	)
	(wire
		(pts
			(xy 231.14 88.9) (xy 231.14 80.01)
		)
		(stroke
			(width 0)
			(type default)
		)
	)
	(wire
		(pts
			(xy 250.19 325.12) (xy 250.19 326.39)
		)
		(stroke
			(width 0)
			(type default)
		)
	)
	(wire
		(pts
			(xy 234.95 62.23) (xy 234.95 66.04)
		)
		(stroke
			(width 0)
			(type default)
		)
	)
	(wire
		(pts
			(xy 172.72 213.36) (xy 172.72 212.09)
		)
		(stroke
			(width 0)
			(type default)
		)
	)
	(wire
		(pts
			(xy 55.88 266.7) (xy 55.88 267.97)
		)
		(stroke
			(width 0)
			(type default)
		)
	)
	(wire
		(pts
			(xy 57.15 242.57) (xy 59.69 242.57)
		)
		(stroke
			(width 0)
			(type default)
		)
	)
	(wire
		(pts
			(xy 92.71 330.2) (xy 100.33 330.2)
		)
		(stroke
			(width 0)
			(type default)
		)
	)
	(wire
		(pts
			(xy 181.61 205.74) (xy 182.88 205.74)
		)
		(stroke
			(width 0)
			(type default)
		)
	)
	(wire
		(pts
			(xy 83.82 384.81) (xy 83.82 387.35)
		)
		(stroke
			(width 0)
			(type default)
		)
	)
	(wire
		(pts
			(xy 72.39 168.91) (xy 72.39 171.45)
		)
		(stroke
			(width 0)
			(type default)
		)
	)
	(wire
		(pts
			(xy 232.41 280.67) (xy 232.41 278.13)
		)
		(stroke
			(width 0)
			(type default)
		)
	)
	(wire
		(pts
			(xy 182.88 203.2) (xy 182.88 205.74)
		)
		(stroke
			(width 0)
			(type default)
		)
	)
	(wire
		(pts
			(xy 160.02 354.33) (xy 160.02 356.87)
		)
		(stroke
			(width 0)
			(type default)
		)
	)
	(wire
		(pts
			(xy 54.61 242.57) (xy 57.15 242.57)
		)
		(stroke
			(width 0)
			(type default)
		)
	)
	(wire
		(pts
			(xy 132.08 107.95) (xy 139.7 107.95)
		)
		(stroke
			(width 0)
			(type default)
		)
	)
	(wire
		(pts
			(xy 213.36 280.67) (xy 213.36 287.02)
		)
		(stroke
			(width 0)
			(type default)
		)
	)
	(wire
		(pts
			(xy 139.7 346.71) (xy 151.13 346.71)
		)
		(stroke
			(width 0)
			(type default)
		)
	)
	(wire
		(pts
			(xy 64.77 330.2) (xy 74.93 330.2)
		)
		(stroke
			(width 0)
			(type default)
		)
	)
	(wire
		(pts
			(xy 57.15 251.46) (xy 57.15 252.73)
		)
		(stroke
			(width 0)
			(type default)
		)
	)
	(wire
		(pts
			(xy 212.09 203.2) (xy 220.98 203.2)
		)
		(stroke
			(width 0)
			(type default)
		)
	)
	(wire
		(pts
			(xy 55.88 198.12) (xy 45.72 198.12)
		)
		(stroke
			(width 0)
			(type default)
		)
	)
	(wire
		(pts
			(xy 76.2 198.12) (xy 76.2 199.39)
		)
		(stroke
			(width 0)
			(type default)
		)
	)
	(wire
		(pts
			(xy 30.48 384.81) (xy 33.02 384.81)
		)
		(stroke
			(width 0)
			(type default)
		)
	)
	(wire
		(pts
			(xy 69.85 62.23) (xy 72.39 62.23)
		)
		(stroke
			(width 0)
			(type default)
		)
	)
	(wire
		(pts
			(xy 99.06 359.41) (xy 99.06 361.95)
		)
		(stroke
			(width 0)
			(type default)
		)
	)
	(wire
		(pts
			(xy 24.13 198.12) (xy 29.21 198.12)
		)
		(stroke
			(width 0)
			(type default)
		)
	)
	(wire
		(pts
			(xy 171.45 234.95) (xy 171.45 236.22)
		)
		(stroke
			(width 0)
			(type default)
		)
	)
	(wire
		(pts
			(xy 157.48 251.46) (xy 157.48 254)
		)
		(stroke
			(width 0)
			(type default)
		)
	)
	(wire
		(pts
			(xy 100.33 344.17) (xy 101.6 344.17)
		)
		(stroke
			(width 0)
			(type default)
		)
	)
	(wire
		(pts
			(xy 123.19 257.81) (xy 123.19 259.08)
		)
		(stroke
			(width 0)
			(type default)
		)
	)
	(wire
		(pts
			(xy 231.14 300.99) (xy 231.14 313.69)
		)
		(stroke
			(width 0)
			(type default)
		)
	)
	(wire
		(pts
			(xy 132.08 120.65) (xy 133.35 120.65)
		)
		(stroke
			(width 0)
			(type default)
		)
	)
	(wire
		(pts
			(xy 66.04 198.12) (xy 66.04 199.39)
		)
		(stroke
			(width 0)
			(type default)
		)
	)
	(wire
		(pts
			(xy 250.19 316.23) (xy 250.19 320.04)
		)
		(stroke
			(width 0)
			(type default)
		)
	)
	(wire
		(pts
			(xy 57.15 330.2) (xy 64.77 330.2)
		)
		(stroke
			(width 0)
			(type default)
		)
	)
	(wire
		(pts
			(xy 111.76 236.22) (xy 111.76 238.76)
		)
		(stroke
			(width 0)
			(type default)
		)
	)
	(wire
		(pts
			(xy 231.14 313.69) (xy 232.41 313.69)
		)
		(stroke
			(width 0)
			(type default)
		)
	)
	(wire
		(pts
			(xy 240.03 123.19) (xy 240.03 128.27)
		)
		(stroke
			(width 0)
			(type default)
		)
	)
	(wire
		(pts
			(xy 256.54 203.2) (xy 262.89 203.2)
		)
		(stroke
			(width 0)
			(type default)
		)
	)
	(wire
		(pts
			(xy 52.07 387.35) (xy 53.34 387.35)
		)
		(stroke
			(width 0)
			(type default)
		)
	)
	(wire
		(pts
			(xy 265.43 312.42) (xy 265.43 318.77)
		)
		(stroke
			(width 0)
			(type default)
		)
	)
	(wire
		(pts
			(xy 36.83 330.2) (xy 45.72 330.2)
		)
		(stroke
			(width 0)
			(type default)
		)
	)
	(wire
		(pts
			(xy 62.23 107.95) (xy 62.23 110.49)
		)
		(stroke
			(width 0)
			(type default)
		)
	)
	(wire
		(pts
			(xy 196.85 113.03) (xy 196.85 114.3)
		)
		(stroke
			(width 0)
			(type default)
		)
	)
	(wire
		(pts
			(xy 46.99 392.43) (xy 46.99 394.97)
		)
		(stroke
			(width 0)
			(type default)
		)
	)
	(wire
		(pts
			(xy 128.27 218.44) (xy 130.81 218.44)
		)
		(stroke
			(width 0)
			(type default)
		)
	)
	(wire
		(pts
			(xy 74.93 356.87) (xy 74.93 359.41)
		)
		(stroke
			(width 0)
			(type default)
		)
	)
	(wire
		(pts
			(xy 74.93 330.2) (xy 74.93 332.74)
		)
		(stroke
			(width 0)
			(type default)
		)
	)
	(wire
		(pts
			(xy 124.46 238.76) (xy 130.81 238.76)
		)
		(stroke
			(width 0)
			(type default)
		)
	)
	(wire
		(pts
			(xy 96.52 212.09) (xy 96.52 213.36)
		)
		(stroke
			(width 0)
			(type default)
		)
	)
	(wire
		(pts
			(xy 151.13 353.06) (xy 151.13 354.33)
		)
		(stroke
			(width 0)
			(type default)
		)
	)
	(wire
		(pts
			(xy 72.39 52.07) (xy 72.39 57.15)
		)
		(stroke
			(width 0)
			(type default)
		)
	)
	(wire
		(pts
			(xy 116.84 208.28) (xy 128.27 208.28)
		)
		(stroke
			(width 0)
			(type default)
		)
	)
	(wire
		(pts
			(xy 133.35 113.03) (xy 133.35 115.57)
		)
		(stroke
			(width 0)
			(type default)
		)
	)
	(wire
		(pts
			(xy 229.87 358.14) (xy 229.87 364.49)
		)
		(stroke
			(width 0)
			(type default)
		)
	)
	(wire
		(pts
			(xy 45.72 148.59) (xy 46.99 148.59)
		)
		(stroke
			(width 0)
			(type default)
		)
	)
	(wire
		(pts
			(xy 171.45 236.22) (xy 168.91 236.22)
		)
		(stroke
			(width 0)
			(type default)
		)
	)
	(wire
		(pts
			(xy 132.08 77.47) (xy 154.94 77.47)
		)
		(stroke
			(width 0)
			(type default)
		)
	)
	(wire
		(pts
			(xy 133.35 163.83) (xy 133.35 166.37)
		)
		(stroke
			(width 0)
			(type default)
		)
	)
	(wire
		(pts
			(xy 160.02 134.62) (xy 160.02 138.43)
		)
		(stroke
			(width 0)
			(type default)
		)
	)
	(wire
		(pts
			(xy 60.96 62.23) (xy 64.77 62.23)
		)
		(stroke
			(width 0)
			(type default)
		)
	)
	(wire
		(pts
			(xy 111.76 220.98) (xy 130.81 220.98)
		)
		(stroke
			(width 0)
			(type default)
		)
	)
	(wire
		(pts
			(xy 120.65 359.41) (xy 121.92 359.41)
		)
		(stroke
			(width 0)
			(type default)
		)
	)
	(wire
		(pts
			(xy 172.72 74.93) (xy 181.61 74.93)
		)
		(stroke
			(width 0)
			(type default)
		)
	)
	(wire
		(pts
			(xy 115.57 238.76) (xy 119.38 238.76)
		)
		(stroke
			(width 0)
			(type default)
		)
	)
	(wire
		(pts
			(xy 140.97 143.51) (xy 148.59 143.51)
		)
		(stroke
			(width 0)
			(type default)
		)
	)
	(wire
		(pts
			(xy 265.43 300.99) (xy 265.43 307.34)
		)
		(stroke
			(width 0)
			(type default)
		)
	)
	(wire
		(pts
			(xy 234.95 71.12) (xy 234.95 74.93)
		)
		(stroke
			(width 0)
			(type default)
		)
	)
	(wire
		(pts
			(xy 240.03 203.2) (xy 242.57 203.2)
		)
		(stroke
			(width 0)
			(type default)
		)
	)
	(wire
		(pts
			(xy 39.37 102.87) (xy 43.18 102.87)
		)
		(stroke
			(width 0)
			(type default)
		)
	)
	(wire
		(pts
			(xy 222.25 123.19) (xy 224.79 123.19)
		)
		(stroke
			(width 0)
			(type default)
		)
	)
	(wire
		(pts
			(xy 27.94 77.47) (xy 73.66 77.47)
		)
		(stroke
			(width 0)
			(type default)
		)
	)
	(wire
		(pts
			(xy 91.44 387.35) (xy 91.44 384.81)
		)
		(stroke
			(width 0)
			(type default)
		)
	)
	(wire
		(pts
			(xy 43.18 102.87) (xy 43.18 105.41)
		)
		(stroke
			(width 0)
			(type default)
		)
	)
	(wire
		(pts
			(xy 71.12 161.29) (xy 73.66 161.29)
		)
		(stroke
			(width 0)
			(type default)
		)
	)
	(wire
		(pts
			(xy 173.99 55.88) (xy 173.99 58.42)
		)
		(stroke
			(width 0)
			(type default)
		)
	)
	(wire
		(pts
			(xy 74.93 337.82) (xy 74.93 340.36)
		)
		(stroke
			(width 0)
			(type default)
		)
	)
	(wire
		(pts
			(xy 251.46 278.13) (xy 251.46 280.67)
		)
		(stroke
			(width 0)
			(type default)
		)
	)
	(wire
		(pts
			(xy 140.97 133.35) (xy 148.59 133.35)
		)
		(stroke
			(width 0)
			(type default)
		)
	)
	(wire
		(pts
			(xy 251.46 285.75) (xy 251.46 287.02)
		)
		(stroke
			(width 0)
			(type default)
		)
	)
	(wire
		(pts
			(xy 154.94 77.47) (xy 162.56 77.47)
		)
		(stroke
			(width 0)
			(type default)
		)
	)
	(wire
		(pts
			(xy 213.36 262.89) (xy 224.79 262.89)
		)
		(stroke
			(width 0)
			(type default)
		)
	)
	(wire
		(pts
			(xy 128.27 210.82) (xy 128.27 212.09)
		)
		(stroke
			(width 0)
			(type default)
		)
	)
	(wire
		(pts
			(xy 247.65 203.2) (xy 250.19 203.2)
		)
		(stroke
			(width 0)
			(type default)
		)
	)
	(wire
		(pts
			(xy 46.99 153.67) (xy 46.99 160.02)
		)
		(stroke
			(width 0)
			(type default)
		)
	)
	(wire
		(pts
			(xy 71.12 384.81) (xy 83.82 384.81)
		)
		(stroke
			(width 0)
			(type default)
		)
	)
	(wire
		(pts
			(xy 181.61 358.14) (xy 181.61 364.49)
		)
		(stroke
			(width 0)
			(type default)
		)
	)
	(wire
		(pts
			(xy 132.08 64.77) (xy 133.35 64.77)
		)
		(stroke
			(width 0)
			(type default)
		)
	)
	(wire
		(pts
			(xy 46.99 58.42) (xy 46.99 60.96)
		)
		(stroke
			(width 0)
			(type default)
		)
	)
	(wire
		(pts
			(xy 128.27 208.28) (xy 130.81 208.28)
		)
		(stroke
			(width 0)
			(type default)
		)
	)
	(wire
		(pts
			(xy 119.38 346.71) (xy 130.81 346.71)
		)
		(stroke
			(width 0)
			(type default)
		)
	)
	(wire
		(pts
			(xy 109.22 208.28) (xy 111.76 208.28)
		)
		(stroke
			(width 0)
			(type default)
		)
	)
	(wire
		(pts
			(xy 233.68 218.44) (xy 233.68 219.71)
		)
		(stroke
			(width 0)
			(type default)
		)
	)
	(wire
		(pts
			(xy 160.02 138.43) (xy 167.64 138.43)
		)
		(stroke
			(width 0)
			(type default)
		)
	)
	(wire
		(pts
			(xy 250.19 203.2) (xy 256.54 203.2)
		)
		(stroke
			(width 0)
			(type default)
		)
	)
	(wire
		(pts
			(xy 76.2 198.12) (xy 66.04 198.12)
		)
		(stroke
			(width 0)
			(type default)
		)
	)
	(wire
		(pts
			(xy 222.25 300.99) (xy 223.52 300.99)
		)
		(stroke
			(width 0)
			(type default)
		)
	)
	(wire
		(pts
			(xy 156.21 203.2) (xy 182.88 203.2)
		)
		(stroke
			(width 0)
			(type default)
		)
	)
	(wire
		(pts
			(xy 40.64 198.12) (xy 45.72 198.12)
		)
		(stroke
			(width 0)
			(type default)
		)
	)
	(wire
		(pts
			(xy 81.28 356.87) (xy 81.28 359.41)
		)
		(stroke
			(width 0)
			(type default)
		)
	)
	(wire
		(pts
			(xy 66.04 349.25) (xy 57.15 349.25)
		)
		(stroke
			(width 0)
			(type default)
		)
	)
	(wire
		(pts
			(xy 72.39 140.97) (xy 72.39 138.43)
		)
		(stroke
			(width 0)
			(type default)
		)
	)
	(wire
		(pts
			(xy 153.67 46.99) (xy 153.67 50.8)
		)
		(stroke
			(width 0)
			(type default)
		)
	)
	(wire
		(pts
			(xy 237.49 345.44) (xy 237.49 346.71)
		)
		(stroke
			(width 0)
			(type default)
		)
	)
	(wire
		(pts
			(xy 111.76 228.6) (xy 111.76 229.87)
		)
		(stroke
			(width 0)
			(type default)
		)
	)
	(wire
		(pts
			(xy 45.72 144.78) (xy 50.8 144.78)
		)
		(stroke
			(width 0)
			(type default)
		)
	)
	(wire
		(pts
			(xy 72.39 138.43) (xy 73.66 138.43)
		)
		(stroke
			(width 0)
			(type default)
		)
	)
	(wire
		(pts
			(xy 234.95 62.23) (xy 243.84 62.23)
		)
		(stroke
			(width 0)
			(type default)
		)
	)
	(wire
		(pts
			(xy 168.91 233.68) (xy 168.91 236.22)
		)
		(stroke
			(width 0)
			(type default)
		)
	)
	(wire
		(pts
			(xy 69.85 107.95) (xy 73.66 107.95)
		)
		(stroke
			(width 0)
			(type default)
		)
	)
	(wire
		(pts
			(xy 96.52 204.47) (xy 96.52 205.74)
		)
		(stroke
			(width 0)
			(type default)
		)
	)
	(wire
		(pts
			(xy 36.83 328.93) (xy 36.83 330.2)
		)
		(stroke
			(width 0)
			(type default)
		)
	)
	(wire
		(pts
			(xy 52.07 394.97) (xy 52.07 387.35)
		)
		(stroke
			(width 0)
			(type default)
		)
	)
	(wire
		(pts
			(xy 115.57 236.22) (xy 119.38 236.22)
		)
		(stroke
			(width 0)
			(type default)
		)
	)
	(wire
		(pts
			(xy 46.99 148.59) (xy 46.99 153.67)
		)
		(stroke
			(width 0)
			(type default)
		)
	)
	(wire
		(pts
			(xy 130.81 346.71) (xy 134.62 346.71)
		)
		(stroke
			(width 0)
			(type default)
		)
	)
	(wire
		(pts
			(xy 231.14 320.04) (xy 231.14 316.23)
		)
		(stroke
			(width 0)
			(type default)
		)
	)
	(wire
		(pts
			(xy 26.67 77.47) (xy 27.94 77.47)
		)
		(stroke
			(width 0)
			(type default)
		)
	)
	(wire
		(pts
			(xy 93.98 351.79) (xy 93.98 355.6)
		)
		(stroke
			(width 0)
			(type default)
		)
	)
	(wire
		(pts
			(xy 182.88 46.99) (xy 182.88 50.8)
		)
		(stroke
			(width 0)
			(type default)
		)
	)
	(wire
		(pts
			(xy 127 344.17) (xy 130.81 344.17)
		)
		(stroke
			(width 0)
			(type default)
		)
	)
	(wire
		(pts
			(xy 127 231.14) (xy 130.81 231.14)
		)
		(stroke
			(width 0)
			(type default)
		)
	)
	(wire
		(pts
			(xy 173.99 46.99) (xy 173.99 50.8)
		)
		(stroke
			(width 0)
			(type default)
		)
	)
	(wire
		(pts
			(xy 130.81 196.85) (xy 130.81 198.12)
		)
		(stroke
			(width 0)
			(type default)
		)
	)
	(wire
		(pts
			(xy 83.82 330.2) (xy 92.71 330.2)
		)
		(stroke
			(width 0)
			(type default)
		)
	)
	(wire
		(pts
			(xy 73.66 168.91) (xy 72.39 168.91)
		)
		(stroke
			(width 0)
			(type default)
		)
	)
	(wire
		(pts
			(xy 73.66 57.15) (xy 72.39 57.15)
		)
		(stroke
			(width 0)
			(type default)
		)
	)
	(wire
		(pts
			(xy 50.8 156.21) (xy 73.66 156.21)
		)
		(stroke
			(width 0)
			(type default)
		)
	)
	(wire
		(pts
			(xy 203.2 203.2) (xy 203.2 205.74)
		)
		(stroke
			(width 0)
			(type default)
		)
	)
	(wire
		(pts
			(xy 233.68 203.2) (xy 233.68 212.09)
		)
		(stroke
			(width 0)
			(type default)
		)
	)
	(wire
		(pts
			(xy 194.31 129.54) (xy 198.12 129.54)
		)
		(stroke
			(width 0)
			(type default)
		)
	)
	(wire
		(pts
			(xy 220.98 346.71) (xy 229.87 346.71)
		)
		(stroke
			(width 0)
			(type default)
		)
	)
	(wire
		(pts
			(xy 199.39 355.6) (xy 199.39 358.14)
		)
		(stroke
			(width 0)
			(type default)
		)
	)
	(wire
		(pts
			(xy 60.96 92.71) (xy 64.77 92.71)
		)
		(stroke
			(width 0)
			(type default)
		)
	)
	(wire
		(pts
			(xy 181.61 346.71) (xy 181.61 353.06)
		)
		(stroke
			(width 0)
			(type default)
		)
	)
	(wire
		(pts
			(xy 237.49 91.44) (xy 237.49 95.25)
		)
		(stroke
			(width 0)
			(type default)
		)
	)
	(wire
		(pts
			(xy 62.23 120.65) (xy 73.66 120.65)
		)
		(stroke
			(width 0)
			(type default)
		)
	)
	(wire
		(pts
			(xy 86.36 204.47) (xy 86.36 207.01)
		)
		(stroke
			(width 0)
			(type default)
		)
	)
	(wire
		(pts
			(xy 60.96 87.63) (xy 60.96 85.09)
		)
		(stroke
			(width 0)
			(type default)
		)
	)
	(wire
		(pts
			(xy 64.77 330.2) (xy 64.77 332.74)
		)
		(stroke
			(width 0)
			(type default)
		)
	)
	(wire
		(pts
			(xy 50.8 165.1) (xy 50.8 175.26)
		)
		(stroke
			(width 0)
			(type default)
		)
	)
	(wire
		(pts
			(xy 199.39 346.71) (xy 199.39 350.52)
		)
		(stroke
			(width 0)
			(type default)
		)
	)
	(wire
		(pts
			(xy 185.42 203.2) (xy 194.31 203.2)
		)
		(stroke
			(width 0)
			(type default)
		)
	)
	(wire
		(pts
			(xy 181.61 346.71) (xy 190.5 346.71)
		)
		(stroke
			(width 0)
			(type default)
		)
	)
	(wire
		(pts
			(xy 132.08 125.73) (xy 135.89 125.73)
		)
		(stroke
			(width 0)
			(type default)
		)
	)
	(wire
		(pts
			(xy 45.72 198.12) (xy 45.72 199.39)
		)
		(stroke
			(width 0)
			(type default)
		)
	)
	(wire
		(pts
			(xy 50.8 144.78) (xy 50.8 156.21)
		)
		(stroke
			(width 0)
			(type default)
		)
	)
	(wire
		(pts
			(xy 38.1 384.81) (xy 46.99 384.81)
		)
		(stroke
			(width 0)
			(type default)
		)
	)
	(wire
		(pts
			(xy 212.09 203.2) (xy 212.09 205.74)
		)
		(stroke
			(width 0)
			(type default)
		)
	)
	(wire
		(pts
			(xy 144.78 54.61) (xy 148.59 54.61)
		)
		(stroke
			(width 0)
			(type default)
		)
	)
	(wire
		(pts
			(xy 55.88 260.35) (xy 55.88 261.62)
		)
		(stroke
			(width 0)
			(type default)
		)
	)
	(wire
		(pts
			(xy 250.19 212.09) (xy 250.19 234.95)
		)
		(stroke
			(width 0)
			(type default)
		)
	)
	(wire
		(pts
			(xy 86.36 198.12) (xy 86.36 199.39)
		)
		(stroke
			(width 0)
			(type default)
		)
	)
	(wire
		(pts
			(xy 71.12 148.59) (xy 73.66 148.59)
		)
		(stroke
			(width 0)
			(type default)
		)
	)
	(wire
		(pts
			(xy 46.99 387.35) (xy 46.99 384.81)
		)
		(stroke
			(width 0)
			(type default)
		)
	)
	(wire
		(pts
			(xy 72.39 62.23) (xy 73.66 62.23)
		)
		(stroke
			(width 0)
			(type default)
		)
	)
	(wire
		(pts
			(xy 36.83 330.2) (xy 36.83 334.01)
		)
		(stroke
			(width 0)
			(type default)
		)
	)
	(wire
		(pts
			(xy 247.65 85.09) (xy 247.65 95.25)
		)
		(stroke
			(width 0)
			(type default)
		)
	)
	(wire
		(pts
			(xy 222.25 113.03) (xy 222.25 118.11)
		)
		(stroke
			(width 0)
			(type default)
		)
	)
	(wire
		(pts
			(xy 262.89 203.2) (xy 262.89 208.28)
		)
		(stroke
			(width 0)
			(type default)
		)
	)
	(wire
		(pts
			(xy 140.97 153.67) (xy 160.02 153.67)
		)
		(stroke
			(width 0)
			(type default)
		)
	)
	(wire
		(pts
			(xy 27.94 339.09) (xy 27.94 341.63)
		)
		(stroke
			(width 0)
			(type default)
		)
	)
	(wire
		(pts
			(xy 223.52 62.23) (xy 234.95 62.23)
		)
		(stroke
			(width 0)
			(type default)
		)
	)
	(wire
		(pts
			(xy 196.85 119.38) (xy 196.85 120.65)
		)
		(stroke
			(width 0)
			(type default)
		)
	)
	(wire
		(pts
			(xy 99.06 361.95) (xy 101.6 361.95)
		)
		(stroke
			(width 0)
			(type default)
		)
	)
	(wire
		(pts
			(xy 214.63 346.71) (xy 220.98 346.71)
		)
		(stroke
			(width 0)
			(type default)
		)
	)
	(wire
		(pts
			(xy 45.72 204.47) (xy 45.72 207.01)
		)
		(stroke
			(width 0)
			(type default)
		)
	)
	(wire
		(pts
			(xy 45.72 242.57) (xy 49.53 242.57)
		)
		(stroke
			(width 0)
			(type default)
		)
	)
	(wire
		(pts
			(xy 172.72 241.3) (xy 172.72 245.11)
		)
		(stroke
			(width 0)
			(type default)
		)
	)
	(wire
		(pts
			(xy 54.61 58.42) (xy 54.61 60.96)
		)
		(stroke
			(width 0)
			(type default)
		)
	)
	(wire
		(pts
			(xy 60.96 52.07) (xy 64.77 52.07)
		)
		(stroke
			(width 0)
			(type default)
		)
	)
	(wire
		(pts
			(xy 132.08 158.75) (xy 135.89 158.75)
		)
		(stroke
			(width 0)
			(type default)
		)
	)
	(wire
		(pts
			(xy 234.95 74.93) (xy 247.65 74.93)
		)
		(stroke
			(width 0)
			(type default)
		)
	)
	(wire
		(pts
			(xy 130.81 210.82) (xy 128.27 210.82)
		)
		(stroke
			(width 0)
			(type default)
		)
	)
	(wire
		(pts
			(xy 69.85 46.99) (xy 73.66 46.99)
		)
		(stroke
			(width 0)
			(type default)
		)
	)
	(wire
		(pts
			(xy 160.02 353.06) (xy 160.02 354.33)
		)
		(stroke
			(width 0)
			(type default)
		)
	)
	(wire
		(pts
			(xy 25.4 29.21) (xy 25.4 34.29)
		)
		(stroke
			(width 0)
			(type default)
		)
	)
	(wire
		(pts
			(xy 132.08 143.51) (xy 135.89 143.51)
		)
		(stroke
			(width 0)
			(type default)
		)
	)
	(wire
		(pts
			(xy 50.8 160.02) (xy 50.8 156.21)
		)
		(stroke
			(width 0)
			(type default)
		)
	)
	(wire
		(pts
			(xy 203.2 129.54) (xy 217.17 129.54)
		)
		(stroke
			(width 0)
			(type default)
		)
	)
	(wire
		(pts
			(xy 46.99 266.7) (xy 46.99 267.97)
		)
		(stroke
			(width 0)
			(type default)
		)
	)
	(wire
		(pts
			(xy 60.96 82.55) (xy 64.77 82.55)
		)
		(stroke
			(width 0)
			(type default)
		)
	)
	(wire
		(pts
			(xy 133.35 115.57) (xy 133.35 116.84)
		)
		(stroke
			(width 0)
			(type default)
		)
	)
	(wire
		(pts
			(xy 229.87 353.06) (xy 229.87 346.71)
		)
		(stroke
			(width 0)
			(type default)
		)
	)
	(wire
		(pts
			(xy 137.16 359.41) (xy 127 359.41)
		)
		(stroke
			(width 0)
			(type default)
		)
	)
	(wire
		(pts
			(xy 156.21 251.46) (xy 157.48 251.46)
		)
		(stroke
			(width 0)
			(type default)
		)
	)
	(wire
		(pts
			(xy 115.57 218.44) (xy 128.27 218.44)
		)
		(stroke
			(width 0)
			(type default)
		)
	)
	(wire
		(pts
			(xy 181.61 87.63) (xy 181.61 88.9)
		)
		(stroke
			(width 0)
			(type default)
		)
	)
	(wire
		(pts
			(xy 204.47 119.38) (xy 204.47 120.65)
		)
		(stroke
			(width 0)
			(type default)
		)
	)
	(wire
		(pts
			(xy 60.96 62.23) (xy 60.96 67.31)
		)
		(stroke
			(width 0)
			(type default)
		)
	)
	(wire
		(pts
			(xy 214.63 120.65) (xy 224.79 120.65)
		)
		(stroke
			(width 0)
			(type default)
		)
	)
	(wire
		(pts
			(xy 138.43 59.69) (xy 148.59 59.69)
		)
		(stroke
			(width 0)
			(type default)
		)
	)
	(wire
		(pts
			(xy 69.85 110.49) (xy 73.66 110.49)
		)
		(stroke
			(width 0)
			(type default)
		)
	)
	(wire
		(pts
			(xy 120.65 359.41) (xy 119.38 359.41)
		)
		(stroke
			(width 0)
			(type default)
		)
	)
	(wire
		(pts
			(xy 62.23 138.43) (xy 64.77 138.43)
		)
		(stroke
			(width 0)
			(type default)
		)
	)
	(wire
		(pts
			(xy 132.08 148.59) (xy 135.89 148.59)
		)
		(stroke
			(width 0)
			(type default)
		)
	)
	(wire
		(pts
			(xy 203.2 203.2) (xy 212.09 203.2)
		)
		(stroke
			(width 0)
			(type default)
		)
	)
	(wire
		(pts
			(xy 151.13 346.71) (xy 151.13 347.98)
		)
		(stroke
			(width 0)
			(type default)
		)
	)
	(wire
		(pts
			(xy 132.08 69.85) (xy 133.35 69.85)
		)
		(stroke
			(width 0)
			(type default)
		)
	)
	(wire
		(pts
			(xy 224.79 232.41) (xy 240.03 232.41)
		)
		(stroke
			(width 0)
			(type default)
		)
	)
	(wire
		(pts
			(xy 194.31 203.2) (xy 203.2 203.2)
		)
		(stroke
			(width 0)
			(type default)
		)
	)
	(wire
		(pts
			(xy 153.67 46.99) (xy 163.83 46.99)
		)
		(stroke
			(width 0)
			(type default)
		)
	)
	(wire
		(pts
			(xy 168.91 231.14) (xy 156.21 231.14)
		)
		(stroke
			(width 0)
			(type default)
		)
	)
	(wire
		(pts
			(xy 250.19 275.59) (xy 256.54 275.59)
		)
		(stroke
			(width 0)
			(type default)
		)
	)
	(wire
		(pts
			(xy 99.06 361.95) (xy 99.06 363.22)
		)
		(stroke
			(width 0)
			(type default)
		)
	)
	(wire
		(pts
			(xy 27.94 60.96) (xy 34.29 60.96)
		)
		(stroke
			(width 0)
			(type default)
		)
	)
	(wire
		(pts
			(xy 29.21 198.12) (xy 35.56 198.12)
		)
		(stroke
			(width 0)
			(type default)
		)
	)
	(wire
		(pts
			(xy 160.02 125.73) (xy 160.02 129.54)
		)
		(stroke
			(width 0)
			(type default)
		)
	)
	(wire
		(pts
			(xy 146.05 125.73) (xy 146.05 128.27)
		)
		(stroke
			(width 0)
			(type default)
		)
	)
	(wire
		(pts
			(xy 156.21 220.98) (xy 224.79 220.98)
		)
		(stroke
			(width 0)
			(type default)
		)
	)
	(wire
		(pts
			(xy 130.81 251.46) (xy 123.19 251.46)
		)
		(stroke
			(width 0)
			(type default)
		)
	)
	(wire
		(pts
			(xy 240.03 232.41) (xy 240.03 212.09)
		)
		(stroke
			(width 0)
			(type default)
		)
	)
	(wire
		(pts
			(xy 132.08 90.17) (xy 139.7 90.17)
		)
		(stroke
			(width 0)
			(type default)
		)
	)
	(wire
		(pts
			(xy 62.23 110.49) (xy 64.77 110.49)
		)
		(stroke
			(width 0)
			(type default)
		)
	)
	(wire
		(pts
			(xy 46.99 257.81) (xy 46.99 260.35)
		)
		(stroke
			(width 0)
			(type default)
		)
	)
	(wire
		(pts
			(xy 224.79 275.59) (xy 224.79 280.67)
		)
		(stroke
			(width 0)
			(type default)
		)
	)
	(wire
		(pts
			(xy 46.99 58.42) (xy 54.61 58.42)
		)
		(stroke
			(width 0)
			(type default)
		)
	)
	(wire
		(pts
			(xy 115.57 236.22) (xy 115.57 238.76)
		)
		(stroke
			(width 0)
			(type default)
		)
	)
	(wire
		(pts
			(xy 168.91 236.22) (xy 167.64 236.22)
		)
		(stroke
			(width 0)
			(type default)
		)
	)
	(wire
		(pts
			(xy 171.45 228.6) (xy 168.91 228.6)
		)
		(stroke
			(width 0)
			(type default)
		)
	)
	(wire
		(pts
			(xy 232.41 285.75) (xy 232.41 287.02)
		)
		(stroke
			(width 0)
			(type default)
		)
	)
	(wire
		(pts
			(xy 121.92 369.57) (xy 120.65 369.57)
		)
		(stroke
			(width 0)
			(type default)
		)
	)
	(wire
		(pts
			(xy 83.82 330.2) (xy 83.82 332.74)
		)
		(stroke
			(width 0)
			(type default)
		)
	)
	(wire
		(pts
			(xy 133.35 116.84) (xy 133.35 118.11)
		)
		(stroke
			(width 0)
			(type default)
		)
	)
	(wire
		(pts
			(xy 220.98 210.82) (xy 220.98 212.09)
		)
		(stroke
			(width 0)
			(type default)
		)
	)
	(wire
		(pts
			(xy 133.35 116.84) (xy 148.59 116.84)
		)
		(stroke
			(width 0)
			(type default)
		)
	)
	(wire
		(pts
			(xy 172.72 256.54) (xy 172.72 257.81)
		)
		(stroke
			(width 0)
			(type default)
		)
	)
	(wire
		(pts
			(xy 57.15 242.57) (xy 57.15 246.38)
		)
		(stroke
			(width 0)
			(type default)
		)
	)
	(wire
		(pts
			(xy 213.36 262.89) (xy 213.36 275.59)
		)
		(stroke
			(width 0)
			(type default)
		)
	)
	(wire
		(pts
			(xy 86.36 198.12) (xy 96.52 198.12)
		)
		(stroke
			(width 0)
			(type default)
		)
	)
	(wire
		(pts
			(xy 168.91 231.14) (xy 168.91 228.6)
		)
		(stroke
			(width 0)
			(type default)
		)
	)
	(wire
		(pts
			(xy 246.38 121.92) (xy 246.38 120.65)
		)
		(stroke
			(width 0)
			(type default)
		)
	)
	(wire
		(pts
			(xy 185.42 210.82) (xy 185.42 212.09)
		)
		(stroke
			(width 0)
			(type default)
		)
	)
	(wire
		(pts
			(xy 40.64 68.58) (xy 40.64 72.39)
		)
		(stroke
			(width 0)
			(type default)
		)
	)
	(wire
		(pts
			(xy 222.25 129.54) (xy 222.25 123.19)
		)
		(stroke
			(width 0)
			(type default)
		)
	)
	(wire
		(pts
			(xy 217.17 129.54) (xy 217.17 130.81)
		)
		(stroke
			(width 0)
			(type default)
		)
	)
	(wire
		(pts
			(xy 46.99 165.1) (xy 46.99 175.26)
		)
		(stroke
			(width 0)
			(type default)
		)
	)
	(wire
		(pts
			(xy 153.67 55.88) (xy 153.67 58.42)
		)
		(stroke
			(width 0)
			(type default)
		)
	)
	(wire
		(pts
			(xy 156.21 223.52) (xy 222.25 223.52)
		)
		(stroke
			(width 0)
			(type default)
		)
	)
	(wire
		(pts
			(xy 185.42 203.2) (xy 185.42 205.74)
		)
		(stroke
			(width 0)
			(type default)
		)
	)
	(wire
		(pts
			(xy 227.33 88.9) (xy 231.14 88.9)
		)
		(stroke
			(width 0)
			(type default)
		)
	)
	(wire
		(pts
			(xy 231.14 300.99) (xy 241.3 300.99)
		)
		(stroke
			(width 0)
			(type default)
		)
	)
	(wire
		(pts
			(xy 182.88 46.99) (xy 187.96 46.99)
		)
		(stroke
			(width 0)
			(type default)
		)
	)
	(wire
		(pts
			(xy 25.4 60.96) (xy 27.94 60.96)
		)
		(stroke
			(width 0)
			(type default)
		)
	)
	(wire
		(pts
			(xy 27.94 330.2) (xy 36.83 330.2)
		)
		(stroke
			(width 0)
			(type default)
		)
	)
	(wire
		(pts
			(xy 172.72 205.74) (xy 176.53 205.74)
		)
		(stroke
			(width 0)
			(type default)
		)
	)
	(wire
		(pts
			(xy 46.99 384.81) (xy 53.34 384.81)
		)
		(stroke
			(width 0)
			(type default)
		)
	)
	(wire
		(pts
			(xy 151.13 354.33) (xy 160.02 354.33)
		)
		(stroke
			(width 0)
			(type default)
		)
	)
	(wire
		(pts
			(xy 212.09 210.82) (xy 212.09 212.09)
		)
		(stroke
			(width 0)
			(type default)
		)
	)
	(wire
		(pts
			(xy 172.72 358.14) (xy 172.72 364.49)
		)
		(stroke
			(width 0)
			(type default)
		)
	)
	(wire
		(pts
			(xy 83.82 392.43) (xy 83.82 394.97)
		)
		(stroke
			(width 0)
			(type default)
		)
	)
	(wire
		(pts
			(xy 264.16 121.92) (xy 264.16 118.11)
		)
		(stroke
			(width 0)
			(type default)
		)
	)
	(wire
		(pts
			(xy 24.13 330.2) (xy 27.94 330.2)
		)
		(stroke
			(width 0)
			(type default)
		)
	)
	(wire
		(pts
			(xy 171.45 229.87) (xy 171.45 228.6)
		)
		(stroke
			(width 0)
			(type default)
		)
	)
	(wire
		(pts
			(xy 162.56 77.47) (xy 162.56 82.55)
		)
		(stroke
			(width 0)
			(type default)
		)
	)
	(wire
		(pts
			(xy 60.96 46.99) (xy 60.96 52.07)
		)
		(stroke
			(width 0)
			(type default)
		)
	)
	(wire
		(pts
			(xy 46.99 66.04) (xy 46.99 67.31)
		)
		(stroke
			(width 0)
			(type default)
		)
	)
	(wire
		(pts
			(xy 254 300.99) (xy 255.27 300.99)
		)
		(stroke
			(width 0)
			(type default)
		)
	)
	(wire
		(pts
			(xy 86.36 198.12) (xy 76.2 198.12)
		)
		(stroke
			(width 0)
			(type default)
		)
	)
	(wire
		(pts
			(xy 73.66 67.31) (xy 72.39 67.31)
		)
		(stroke
			(width 0)
			(type default)
		)
	)
	(wire
		(pts
			(xy 50.8 82.55) (xy 60.96 82.55)
		)
		(stroke
			(width 0)
			(type default)
		)
	)
	(wire
		(pts
			(xy 127 228.6) (xy 130.81 228.6)
		)
		(stroke
			(width 0)
			(type default)
		)
	)
	(wire
		(pts
			(xy 74.93 349.25) (xy 81.28 349.25)
		)
		(stroke
			(width 0)
			(type default)
		)
	)
	(wire
		(pts
			(xy 66.04 247.65) (xy 66.04 252.73)
		)
		(stroke
			(width 0)
			(type default)
		)
	)
	(wire
		(pts
			(xy 132.08 46.99) (xy 153.67 46.99)
		)
		(stroke
			(width 0)
			(type default)
		)
	)
	(wire
		(pts
			(xy 220.98 353.06) (xy 220.98 346.71)
		)
		(stroke
			(width 0)
			(type default)
		)
	)
	(wire
		(pts
			(xy 50.8 330.2) (xy 57.15 330.2)
		)
		(stroke
			(width 0)
			(type default)
		)
	)
	(wire
		(pts
			(xy 130.81 203.2) (xy 130.81 198.12)
		)
		(stroke
			(width 0)
			(type default)
		)
	)
	(wire
		(pts
			(xy 190.5 358.14) (xy 190.5 364.49)
		)
		(stroke
			(width 0)
			(type default)
		)
	)
	(wire
		(pts
			(xy 120.65 369.57) (xy 120.65 359.41)
		)
		(stroke
			(width 0)
			(type default)
		)
	)
	(wire
		(pts
			(xy 162.56 87.63) (xy 162.56 88.9)
		)
		(stroke
			(width 0)
			(type default)
		)
	)
	(wire
		(pts
			(xy 27.94 330.2) (xy 27.94 334.01)
		)
		(stroke
			(width 0)
			(type default)
		)
	)
	(wire
		(pts
			(xy 247.65 69.85) (xy 247.65 74.93)
		)
		(stroke
			(width 0)
			(type default)
		)
	)
	(wire
		(pts
			(xy 240.03 205.74) (xy 240.03 203.2)
		)
		(stroke
			(width 0)
			(type default)
		)
	)
	(wire
		(pts
			(xy 222.25 118.11) (xy 224.79 118.11)
		)
		(stroke
			(width 0)
			(type default)
		)
	)
	(wire
		(pts
			(xy 132.08 85.09) (xy 133.35 85.09)
		)
		(stroke
			(width 0)
			(type default)
		)
	)
	(wire
		(pts
			(xy 251.46 270.51) (xy 251.46 278.13)
		)
		(stroke
			(width 0)
			(type default)
		)
	)
	(wire
		(pts
			(xy 69.85 138.43) (xy 72.39 138.43)
		)
		(stroke
			(width 0)
			(type default)
		)
	)
	(wire
		(pts
			(xy 34.29 60.96) (xy 34.29 63.5)
		)
		(stroke
			(width 0)
			(type default)
		)
	)
	(wire
		(pts
			(xy 194.31 203.2) (xy 194.31 205.74)
		)
		(stroke
			(width 0)
			(type default)
		)
	)
	(wire
		(pts
			(xy 172.72 207.01) (xy 172.72 205.74)
		)
		(stroke
			(width 0)
			(type default)
		)
	)
	(wire
		(pts
			(xy 34.29 60.96) (xy 40.64 60.96)
		)
		(stroke
			(width 0)
			(type default)
		)
	)
	(wire
		(pts
			(xy 46.99 260.35) (xy 46.99 261.62)
		)
		(stroke
			(width 0)
			(type default)
		)
	)
	(wire
		(pts
			(xy 160.02 346.71) (xy 172.72 346.71)
		)
		(stroke
			(width 0)
			(type default)
		)
	)
	(wire
		(pts
			(xy 132.08 54.61) (xy 139.7 54.61)
		)
		(stroke
			(width 0)
			(type default)
		)
	)
	(wire
		(pts
			(xy 264.16 118.11) (xy 265.43 118.11)
		)
		(stroke
			(width 0)
			(type default)
		)
	)
	(wire
		(pts
			(xy 231.14 316.23) (xy 232.41 316.23)
		)
		(stroke
			(width 0)
			(type default)
		)
	)
	(wire
		(pts
			(xy 223.52 300.99) (xy 231.14 300.99)
		)
		(stroke
			(width 0)
			(type default)
		)
	)
	(wire
		(pts
			(xy 55.88 198.12) (xy 55.88 199.39)
		)
		(stroke
			(width 0)
			(type default)
		)
	)
	(wire
		(pts
			(xy 233.68 203.2) (xy 240.03 203.2)
		)
		(stroke
			(width 0)
			(type default)
		)
	)
	(wire
		(pts
			(xy 91.44 384.81) (xy 99.06 384.81)
		)
		(stroke
			(width 0)
			(type default)
		)
	)
	(wire
		(pts
			(xy 250.19 278.13) (xy 251.46 278.13)
		)
		(stroke
			(width 0)
			(type default)
		)
	)
	(wire
		(pts
			(xy 69.85 92.71) (xy 73.66 92.71)
		)
		(stroke
			(width 0)
			(type default)
		)
	)
	(wire
		(pts
			(xy 26.67 72.39) (xy 40.64 72.39)
		)
		(stroke
			(width 0)
			(type default)
		)
	)
	(wire
		(pts
			(xy 222.25 234.95) (xy 250.19 234.95)
		)
		(stroke
			(width 0)
			(type default)
		)
	)
	(wire
		(pts
			(xy 172.72 87.63) (xy 172.72 88.9)
		)
		(stroke
			(width 0)
			(type default)
		)
	)
	(wire
		(pts
			(xy 69.85 67.31) (xy 72.39 67.31)
		)
		(stroke
			(width 0)
			(type default)
		)
	)
	(wire
		(pts
			(xy 74.93 328.93) (xy 74.93 330.2)
		)
		(stroke
			(width 0)
			(type default)
		)
	)
	(wire
		(pts
			(xy 123.19 241.3) (xy 130.81 241.3)
		)
		(stroke
			(width 0)
			(type default)
		)
	)
	(wire
		(pts
			(xy 123.19 248.92) (xy 123.19 251.46)
		)
		(stroke
			(width 0)
			(type default)
		)
	)
	(wire
		(pts
			(xy 96.52 205.74) (xy 96.52 207.01)
		)
		(stroke
			(width 0)
			(type default)
		)
	)
	(wire
		(pts
			(xy 195.58 113.03) (xy 196.85 113.03)
		)
		(stroke
			(width 0)
			(type default)
		)
	)
	(wire
		(pts
			(xy 248.92 316.23) (xy 250.19 316.23)
		)
		(stroke
			(width 0)
			(type default)
		)
	)
	(wire
		(pts
			(xy 217.17 137.16) (xy 217.17 135.89)
		)
		(stroke
			(width 0)
			(type default)
		)
	)
	(wire
		(pts
			(xy 119.38 354.33) (xy 151.13 354.33)
		)
		(stroke
			(width 0)
			(type default)
		)
	)
	(wire
		(pts
			(xy 255.27 127) (xy 255.27 128.27)
		)
		(stroke
			(width 0)
			(type default)
		)
	)
	(wire
		(pts
			(xy 60.96 87.63) (xy 64.77 87.63)
		)
		(stroke
			(width 0)
			(type default)
		)
	)
	(wire
		(pts
			(xy 43.18 110.49) (xy 43.18 113.03)
		)
		(stroke
			(width 0)
			(type default)
		)
	)
	(wire
		(pts
			(xy 60.96 85.09) (xy 60.96 82.55)
		)
		(stroke
			(width 0)
			(type default)
		)
	)
	(wire
		(pts
			(xy 133.35 82.55) (xy 133.35 85.09)
		)
		(stroke
			(width 0)
			(type default)
		)
	)
	(wire
		(pts
			(xy 204.47 113.03) (xy 214.63 113.03)
		)
		(stroke
			(width 0)
			(type default)
		)
	)
	(wire
		(pts
			(xy 29.21 198.12) (xy 29.21 200.66)
		)
		(stroke
			(width 0)
			(type default)
		)
	)
	(wire
		(pts
			(xy 64.77 337.82) (xy 64.77 340.36)
		)
		(stroke
			(width 0)
			(type default)
		)
	)
	(wire
		(pts
			(xy 81.28 349.25) (xy 101.6 349.25)
		)
		(stroke
			(width 0)
			(type default)
		)
	)
	(wire
		(pts
			(xy 182.88 203.2) (xy 185.42 203.2)
		)
		(stroke
			(width 0)
			(type default)
		)
	)
	(wire
		(pts
			(xy 196.85 113.03) (xy 204.47 113.03)
		)
		(stroke
			(width 0)
			(type default)
		)
	)
	(wire
		(pts
			(xy 182.88 55.88) (xy 182.88 58.42)
		)
		(stroke
			(width 0)
			(type default)
		)
	)
	(wire
		(pts
			(xy 133.35 118.11) (xy 133.35 120.65)
		)
		(stroke
			(width 0)
			(type default)
		)
	)
	(wire
		(pts
			(xy 62.23 107.95) (xy 64.77 107.95)
		)
		(stroke
			(width 0)
			(type default)
		)
	)
	(wire
		(pts
			(xy 72.39 52.07) (xy 73.66 52.07)
		)
		(stroke
			(width 0)
			(type default)
		)
	)
	(wire
		(pts
			(xy 262.89 213.36) (xy 262.89 215.9)
		)
		(stroke
			(width 0)
			(type default)
		)
	)
	(wire
		(pts
			(xy 204.47 113.03) (xy 204.47 114.3)
		)
		(stroke
			(width 0)
			(type default)
		)
	)
	(wire
		(pts
			(xy 132.08 97.79) (xy 139.7 97.79)
		)
		(stroke
			(width 0)
			(type default)
		)
	)
	(wire
		(pts
			(xy 262.89 203.2) (xy 266.7 203.2)
		)
		(stroke
			(width 0)
			(type default)
		)
	)
	(wire
		(pts
			(xy 146.05 125.73) (xy 160.02 125.73)
		)
		(stroke
			(width 0)
			(type default)
		)
	)
	(wire
		(pts
			(xy 262.89 262.89) (xy 269.24 262.89)
		)
		(stroke
			(width 0)
			(type default)
		)
	)
	(wire
		(pts
			(xy 127 226.06) (xy 130.81 226.06)
		)
		(stroke
			(width 0)
			(type default)
		)
	)
	(wire
		(pts
			(xy 100.33 330.2) (xy 100.33 344.17)
		)
		(stroke
			(width 0)
			(type default)
		)
	)
	(wire
		(pts
			(xy 132.08 92.71) (xy 139.7 92.71)
		)
		(stroke
			(width 0)
			(type default)
		)
	)
	(wire
		(pts
			(xy 218.44 88.9) (xy 222.25 88.9)
		)
		(stroke
			(width 0)
			(type default)
		)
	)
	(wire
		(pts
			(xy 62.23 110.49) (xy 52.07 110.49)
		)
		(stroke
			(width 0)
			(type default)
		)
	)
	(wire
		(pts
			(xy 60.96 43.18) (xy 60.96 46.99)
		)
		(stroke
			(width 0)
			(type default)
		)
	)
	(wire
		(pts
			(xy 124.46 236.22) (xy 130.81 236.22)
		)
		(stroke
			(width 0)
			(type default)
		)
	)
	(wire
		(pts
			(xy 237.49 346.71) (xy 241.3 346.71)
		)
		(stroke
			(width 0)
			(type default)
		)
	)
	(wire
		(pts
			(xy 57.15 234.95) (xy 66.04 234.95)
		)
		(stroke
			(width 0)
			(type default)
		)
	)
	(wire
		(pts
			(xy 222.25 129.54) (xy 217.17 129.54)
		)
		(stroke
			(width 0)
			(type default)
		)
	)
	(wire
		(pts
			(xy 119.38 344.17) (xy 121.92 344.17)
		)
		(stroke
			(width 0)
			(type default)
		)
	)
	(wire
		(pts
			(xy 115.57 215.9) (xy 115.57 218.44)
		)
		(stroke
			(width 0)
			(type default)
		)
	)
	(wire
		(pts
			(xy 132.08 163.83) (xy 133.35 163.83)
		)
		(stroke
			(width 0)
			(type default)
		)
	)
	(wire
		(pts
			(xy 92.71 330.2) (xy 92.71 332.74)
		)
		(stroke
			(width 0)
			(type default)
		)
	)
	(wire
		(pts
			(xy 172.72 250.19) (xy 172.72 251.46)
		)
		(stroke
			(width 0)
			(type default)
		)
	)
	(wire
		(pts
			(xy 232.41 161.29) (xy 241.3 161.29)
		)
		(stroke
			(width 0)
			(type default)
		)
	)
	(wire
		(pts
			(xy 156.21 241.3) (xy 172.72 241.3)
		)
		(stroke
			(width 0)
			(type default)
		)
	)
	(wire
		(pts
			(xy 224.79 262.89) (xy 224.79 270.51)
		)
		(stroke
			(width 0)
			(type default)
		)
	)
	(wire
		(pts
			(xy 140.97 128.27) (xy 146.05 128.27)
		)
		(stroke
			(width 0)
			(type default)
		)
	)
	(wire
		(pts
			(xy 240.03 118.11) (xy 255.27 118.11)
		)
		(stroke
			(width 0)
			(type default)
		)
	)
	(wire
		(pts
			(xy 222.25 223.52) (xy 222.25 234.95)
		)
		(stroke
			(width 0)
			(type default)
		)
	)
	(wire
		(pts
			(xy 237.49 80.01) (xy 237.49 86.36)
		)
		(stroke
			(width 0)
			(type default)
		)
	)
	(wire
		(pts
			(xy 60.96 87.63) (xy 60.96 92.71)
		)
		(stroke
			(width 0)
			(type default)
		)
	)
	(wire
		(pts
			(xy 130.81 344.17) (xy 130.81 346.71)
		)
		(stroke
			(width 0)
			(type default)
		)
	)
	(wire
		(pts
			(xy 224.79 262.89) (xy 232.41 262.89)
		)
		(stroke
			(width 0)
			(type default)
		)
	)
	(wire
		(pts
			(xy 162.56 228.6) (xy 156.21 228.6)
		)
		(stroke
			(width 0)
			(type default)
		)
	)
	(wire
		(pts
			(xy 60.96 46.99) (xy 64.77 46.99)
		)
		(stroke
			(width 0)
			(type default)
		)
	)
	(wire
		(pts
			(xy 55.88 204.47) (xy 55.88 207.01)
		)
		(stroke
			(width 0)
			(type default)
		)
	)
	(wire
		(pts
			(xy 115.57 241.3) (xy 115.57 238.76)
		)
		(stroke
			(width 0)
			(type default)
		)
	)
	(wire
		(pts
			(xy 128.27 208.28) (xy 128.27 210.82)
		)
		(stroke
			(width 0)
			(type default)
		)
	)
	(wire
		(pts
			(xy 96.52 198.12) (xy 96.52 199.39)
		)
		(stroke
			(width 0)
			(type default)
		)
	)
	(wire
		(pts
			(xy 109.22 208.28) (xy 109.22 209.55)
		)
		(stroke
			(width 0)
			(type default)
		)
	)
	(wire
		(pts
			(xy 172.72 346.71) (xy 181.61 346.71)
		)
		(stroke
			(width 0)
			(type default)
		)
	)
	(wire
		(pts
			(xy 73.66 140.97) (xy 72.39 140.97)
		)
		(stroke
			(width 0)
			(type default)
		)
	)
	(wire
		(pts
			(xy 34.29 74.93) (xy 73.66 74.93)
		)
		(stroke
			(width 0)
			(type default)
		)
	)
	(wire
		(pts
			(xy 157.48 248.92) (xy 157.48 251.46)
		)
		(stroke
			(width 0)
			(type default)
		)
	)
	(wire
		(pts
			(xy 194.31 210.82) (xy 194.31 212.09)
		)
		(stroke
			(width 0)
			(type default)
		)
	)
	(wire
		(pts
			(xy 250.19 308.61) (xy 250.19 316.23)
		)
		(stroke
			(width 0)
			(type default)
		)
	)
	(wire
		(pts
			(xy 232.41 262.89) (xy 232.41 275.59)
		)
		(stroke
			(width 0)
			(type default)
		)
	)
	(wire
		(pts
			(xy 132.08 105.41) (xy 139.7 105.41)
		)
		(stroke
			(width 0)
			(type default)
		)
	)
	(wire
		(pts
			(xy 96.52 198.12) (xy 130.81 198.12)
		)
		(stroke
			(width 0)
			(type default)
		)
	)
	(wire
		(pts
			(xy 74.93 330.2) (xy 83.82 330.2)
		)
		(stroke
			(width 0)
			(type default)
		)
	)
	(wire
		(pts
			(xy 46.99 260.35) (xy 55.88 260.35)
		)
		(stroke
			(width 0)
			(type default)
		)
	)
	(wire
		(pts
			(xy 132.08 118.11) (xy 133.35 118.11)
		)
		(stroke
			(width 0)
			(type default)
		)
	)
	(wire
		(pts
			(xy 72.39 58.42) (xy 72.39 62.23)
		)
		(stroke
			(width 0)
			(type default)
		)
	)
	(wire
		(pts
			(xy 54.61 66.04) (xy 54.61 67.31)
		)
		(stroke
			(width 0)
			(type default)
		)
	)
	(wire
		(pts
			(xy 220.98 203.2) (xy 233.68 203.2)
		)
		(stroke
			(width 0)
			(type default)
		)
	)
	(wire
		(pts
			(xy 71.12 349.25) (xy 74.93 349.25)
		)
		(stroke
			(width 0)
			(type default)
		)
	)
	(wire
		(pts
			(xy 168.91 228.6) (xy 167.64 228.6)
		)
		(stroke
			(width 0)
			(type default)
		)
	)
	(wire
		(pts
			(xy 255.27 118.11) (xy 264.16 118.11)
		)
		(stroke
			(width 0)
			(type default)
		)
	)
	(wire
		(pts
			(xy 34.29 68.58) (xy 34.29 74.93)
		)
		(stroke
			(width 0)
			(type default)
		)
	)
	(wire
		(pts
			(xy 45.72 260.35) (xy 46.99 260.35)
		)
		(stroke
			(width 0)
			(type default)
		)
	)
	(wire
		(pts
			(xy 132.08 128.27) (xy 135.89 128.27)
		)
		(stroke
			(width 0)
			(type default)
		)
	)
	(wire
		(pts
			(xy 154.94 87.63) (xy 154.94 88.9)
		)
		(stroke
			(width 0)
			(type default)
		)
	)
	(wire
		(pts
			(xy 69.85 82.55) (xy 73.66 82.55)
		)
		(stroke
			(width 0)
			(type default)
		)
	)
	(wire
		(pts
			(xy 181.61 74.93) (xy 181.61 82.55)
		)
		(stroke
			(width 0)
			(type default)
		)
	)
	(wire
		(pts
			(xy 160.02 346.71) (xy 160.02 347.98)
		)
		(stroke
			(width 0)
			(type default)
		)
	)
	(wire
		(pts
			(xy 43.18 102.87) (xy 64.77 102.87)
		)
		(stroke
			(width 0)
			(type default)
		)
	)
	(wire
		(pts
			(xy 96.52 205.74) (xy 130.81 205.74)
		)
		(stroke
			(width 0)
			(type default)
		)
	)
	(wire
		(pts
			(xy 231.14 80.01) (xy 237.49 80.01)
		)
		(stroke
			(width 0)
			(type default)
		)
	)
	(wire
		(pts
			(xy 190.5 346.71) (xy 199.39 346.71)
		)
		(stroke
			(width 0)
			(type default)
		)
	)
	(wire
		(pts
			(xy 66.04 204.47) (xy 66.04 207.01)
		)
		(stroke
			(width 0)
			(type default)
		)
	)
	(wire
		(pts
			(xy 256.54 262.89) (xy 256.54 275.59)
		)
		(stroke
			(width 0)
			(type default)
		)
	)
	(wire
		(pts
			(xy 261.62 300.99) (xy 265.43 300.99)
		)
		(stroke
			(width 0)
			(type default)
		)
	)
	(wire
		(pts
			(xy 60.96 67.31) (xy 64.77 67.31)
		)
		(stroke
			(width 0)
			(type default)
		)
	)
	(wire
		(pts
			(xy 133.35 171.45) (xy 133.35 173.99)
		)
		(stroke
			(width 0)
			(type default)
		)
	)
	(wire
		(pts
			(xy 29.21 205.74) (xy 29.21 207.01)
		)
		(stroke
			(width 0)
			(type default)
		)
	)
	(wire
		(pts
			(xy 114.3 384.81) (xy 118.11 384.81)
		)
		(stroke
			(width 0)
			(type default)
		)
	)
	(wire
		(pts
			(xy 156.21 205.74) (xy 158.75 205.74)
		)
		(stroke
			(width 0)
			(type default)
		)
	)
	(wire
		(pts
			(xy 203.2 210.82) (xy 203.2 212.09)
		)
		(stroke
			(width 0)
			(type default)
		)
	)
	(wire
		(pts
			(xy 264.16 127) (xy 264.16 128.27)
		)
		(stroke
			(width 0)
			(type default)
		)
	)
	(wire
		(pts
			(xy 229.87 346.71) (xy 237.49 346.71)
		)
		(stroke
			(width 0)
			(type default)
		)
	)
	(wire
		(pts
			(xy 255.27 262.89) (xy 256.54 262.89)
		)
		(stroke
			(width 0)
			(type default)
		)
	)
	(wire
		(pts
			(xy 71.12 146.05) (xy 73.66 146.05)
		)
		(stroke
			(width 0)
			(type default)
		)
	)
	(wire
		(pts
			(xy 92.71 337.82) (xy 92.71 340.36)
		)
		(stroke
			(width 0)
			(type default)
		)
	)
	(wire
		(pts
			(xy 162.56 77.47) (xy 184.15 77.47)
		)
		(stroke
			(width 0)
			(type default)
		)
	)
	(wire
		(pts
			(xy 167.64 250.19) (xy 167.64 257.81)
		)
		(stroke
			(width 0)
			(type default)
		)
	)
	(wire
		(pts
			(xy 76.2 204.47) (xy 76.2 207.01)
		)
		(stroke
			(width 0)
			(type default)
		)
	)
	(wire
		(pts
			(xy 219.71 80.01) (xy 222.25 80.01)
		)
		(stroke
			(width 0)
			(type default)
		)
	)
	(wire
		(pts
			(xy 111.76 220.98) (xy 111.76 223.52)
		)
		(stroke
			(width 0)
			(type default)
		)
	)
	(wire
		(pts
			(xy 25.4 39.37) (xy 25.4 43.18)
		)
		(stroke
			(width 0)
			(type default)
		)
	)
	(wire
		(pts
			(xy 93.98 360.68) (xy 93.98 363.22)
		)
		(stroke
			(width 0)
			(type default)
		)
	)
	(wire
		(pts
			(xy 36.83 339.09) (xy 36.83 341.63)
		)
		(stroke
			(width 0)
			(type default)
		)
	)
	(wire
		(pts
			(xy 132.08 82.55) (xy 133.35 82.55)
		)
		(stroke
			(width 0)
			(type default)
		)
	)
	(wire
		(pts
			(xy 154.94 77.47) (xy 154.94 82.55)
		)
		(stroke
			(width 0)
			(type default)
		)
	)
	(wire
		(pts
			(xy 172.72 346.71) (xy 172.72 353.06)
		)
		(stroke
			(width 0)
			(type default)
		)
	)
	(wire
		(pts
			(xy 232.41 262.89) (xy 242.57 262.89)
		)
		(stroke
			(width 0)
			(type default)
		)
	)
	(wire
		(pts
			(xy 140.97 125.73) (xy 146.05 125.73)
		)
		(stroke
			(width 0)
			(type default)
		)
	)
	(wire
		(pts
			(xy 69.85 52.07) (xy 72.39 52.07)
		)
		(stroke
			(width 0)
			(type default)
		)
	)
	(wire
		(pts
			(xy 223.52 325.12) (xy 223.52 326.39)
		)
		(stroke
			(width 0)
			(type default)
		)
	)
	(wire
		(pts
			(xy 57.15 349.25) (xy 57.15 330.2)
		)
		(stroke
			(width 0)
			(type default)
		)
	)
	(wire
		(pts
			(xy 220.98 358.14) (xy 220.98 364.49)
		)
		(stroke
			(width 0)
			(type default)
		)
	)
	(wire
		(pts
			(xy 138.43 49.53) (xy 148.59 49.53)
		)
		(stroke
			(width 0)
			(type default)
		)
	)
	(wire
		(pts
			(xy 231.14 325.12) (xy 231.14 326.39)
		)
		(stroke
			(width 0)
			(type default)
		)
	)
	(wire
		(pts
			(xy 173.99 46.99) (xy 182.88 46.99)
		)
		(stroke
			(width 0)
			(type default)
		)
	)
	(wire
		(pts
			(xy 151.13 346.71) (xy 160.02 346.71)
		)
		(stroke
			(width 0)
			(type default)
		)
	)
	(wire
		(pts
			(xy 66.04 234.95) (xy 66.04 237.49)
		)
		(stroke
			(width 0)
			(type default)
		)
	)
	(wire
		(pts
			(xy 182.88 44.45) (xy 182.88 46.99)
		)
		(stroke
			(width 0)
			(type default)
		)
	)
	(wire
		(pts
			(xy 138.43 69.85) (xy 148.59 69.85)
		)
		(stroke
			(width 0)
			(type default)
		)
	)
	(wire
		(pts
			(xy 220.98 203.2) (xy 220.98 205.74)
		)
		(stroke
			(width 0)
			(type default)
		)
	)
	(wire
		(pts
			(xy 101.6 359.41) (xy 99.06 359.41)
		)
		(stroke
			(width 0)
			(type default)
		)
	)
	(wire
		(pts
			(xy 27.94 60.96) (xy 27.94 63.5)
		)
		(stroke
			(width 0)
			(type default)
		)
	)
	(wire
		(pts
			(xy 218.44 161.29) (xy 227.33 161.29)
		)
		(stroke
			(width 0)
			(type default)
		)
	)
	(wire
		(pts
			(xy 69.85 87.63) (xy 73.66 87.63)
		)
		(stroke
			(width 0)
			(type default)
		)
	)
	(wire
		(pts
			(xy 114.3 218.44) (xy 115.57 218.44)
		)
		(stroke
			(width 0)
			(type default)
		)
	)
	(wire
		(pts
			(xy 163.83 46.99) (xy 173.99 46.99)
		)
		(stroke
			(width 0)
			(type default)
		)
	)
	(wire
		(pts
			(xy 132.08 100.33) (xy 139.7 100.33)
		)
		(stroke
			(width 0)
			(type default)
		)
	)
	(wire
		(pts
			(xy 104.14 384.81) (xy 114.3 384.81)
		)
		(stroke
			(width 0)
			(type default)
		)
	)
	(wire
		(pts
			(xy 46.99 153.67) (xy 73.66 153.67)
		)
		(stroke
			(width 0)
			(type default)
		)
	)
	(wire
		(pts
			(xy 123.19 241.3) (xy 115.57 241.3)
		)
		(stroke
			(width 0)
			(type default)
		)
	)
	(wire
		(pts
			(xy 62.23 118.11) (xy 73.66 118.11)
		)
		(stroke
			(width 0)
			(type default)
		)
	)
	(wire
		(pts
			(xy 224.79 285.75) (xy 224.79 287.02)
		)
		(stroke
			(width 0)
			(type default)
		)
	)
	(wire
		(pts
			(xy 210.82 262.89) (xy 213.36 262.89)
		)
		(stroke
			(width 0)
			(type default)
		)
	)
	(wire
		(pts
			(xy 27.94 68.58) (xy 27.94 77.47)
		)
		(stroke
			(width 0)
			(type default)
		)
	)
	(wire
		(pts
			(xy 248.92 313.69) (xy 255.27 313.69)
		)
		(stroke
			(width 0)
			(type default)
		)
	)
	(wire
		(pts
			(xy 91.44 384.81) (xy 83.82 384.81)
		)
		(stroke
			(width 0)
			(type default)
		)
	)
	(wire
		(pts
			(xy 54.61 58.42) (xy 72.39 58.42)
		)
		(stroke
			(width 0)
			(type default)
		)
	)
	(wire
		(pts
			(xy 246.38 127) (xy 246.38 128.27)
		)
		(stroke
			(width 0)
			(type default)
		)
	)
	(wire
		(pts
			(xy 265.43 300.99) (xy 270.51 300.99)
		)
		(stroke
			(width 0)
			(type default)
		)
	)
	(text "12V source selection"
		(exclude_from_sim no)
		(at 219.71 252.73 0)
		(effects
			(font
				(size 2.54 2.54)
				(bold yes)
			)
			(justify left bottom)
		)
	)
	(text "USB Power Delivery Controller"
		(exclude_from_sim no)
		(at 74.295 20.32 0)
		(effects
			(font
				(size 2.54 2.54)
				(bold yes)
			)
			(justify left bottom)
		)
	)
	(text "PCIE power"
		(exclude_from_sim no)
		(at 233.68 46.99 0)
		(effects
			(font
				(size 2.54 2.54)
				(bold yes)
			)
			(justify left bottom)
		)
	)
	(text "12V Buck-Boost Converter"
		(exclude_from_sim no)
		(at 117.475 189.23 0)
		(effects
			(font
				(size 2.54 2.54)
				(bold yes)
			)
			(justify left bottom)
		)
	)
	(text "3V3 Buck Converter"
		(exclude_from_sim no)
		(at 92.71 321.945 0)
		(effects
			(font
				(size 2.54 2.54)
				(bold yes)
			)
			(justify left bottom)
		)
	)
	(text "UVLO: 4.2V"
		(exclude_from_sim no)
		(at 103.505 202.565 0)
		(effects
			(font
				(size 1.27 1.27)
			)
			(justify left bottom)
		)
	)
	(text "3V3 Fan controller"
		(exclude_from_sim no)
		(at 43.18 373.38 0)
		(effects
			(font
				(size 2.54 2.54)
				(bold yes)
			)
			(justify left bottom)
		)
	)
	(label "TPS_3V3"
		(at 50.8 82.55 0)
		(fields_autoplaced yes)
		(effects
			(font
				(size 1.27 1.27)
			)
			(justify left bottom)
		)
	)
	(label "TPS_3V3"
		(at 52.07 110.49 0)
		(fields_autoplaced yes)
		(effects
			(font
				(size 1.27 1.27)
			)
			(justify left bottom)
		)
	)
	(label "12V0_PCIE_EN"
		(at 228.6 80.01 0)
		(fields_autoplaced yes)
		(effects
			(font
				(size 1.27 1.27)
			)
			(justify left bottom)
		)
	)
	(label "TPS_3V3"
		(at 152.4 125.73 0)
		(fields_autoplaced yes)
		(effects
			(font
				(size 1.27 1.27)
			)
			(justify left bottom)
		)
	)
	(label "DCDC_EN"
		(at 113.03 205.74 180)
		(fields_autoplaced yes)
		(effects
			(font
				(size 1.27 1.27)
			)
			(justify right bottom)
		)
	)
	(label "I_SENSE_N"
		(at 168.91 223.52 180)
		(fields_autoplaced yes)
		(effects
			(font
				(size 1.27 1.27)
			)
			(justify right bottom)
		)
	)
	(label "3V3_PCIE_EN"
		(at 204.47 129.54 0)
		(fields_autoplaced yes)
		(effects
			(font
				(size 1.27 1.27)
			)
			(justify left bottom)
		)
	)
	(label "I_SENSE_P"
		(at 158.75 220.98 0)
		(fields_autoplaced yes)
		(effects
			(font
				(size 1.27 1.27)
			)
			(justify left bottom)
		)
	)
	(label "SMPS_LDO"
		(at 101.6 351.79 180)
		(fields_autoplaced yes)
		(effects
			(font
				(size 1.27 1.27)
			)
			(justify right bottom)
		)
	)
	(label "TPS_3V3"
		(at 132.08 54.61 0)
		(fields_autoplaced yes)
		(effects
			(font
				(size 1.27 1.27)
			)
			(justify left bottom)
		)
	)
	(label "TPS_3V3"
		(at 160.02 153.67 180)
		(fields_autoplaced yes)
		(effects
			(font
				(size 1.27 1.27)
			)
			(justify right bottom)
		)
	)
	(label "DCDC_EN"
		(at 57.15 234.95 0)
		(fields_autoplaced yes)
		(effects
			(font
				(size 1.27 1.27)
			)
			(justify left bottom)
		)
	)
	(label "SMPS_LDO"
		(at 137.16 359.41 180)
		(fields_autoplaced yes)
		(effects
			(font
				(size 1.27 1.27)
			)
			(justify right bottom)
		)
	)
	(label "TPS_3V3"
		(at 50.8 175.26 90)
		(fields_autoplaced yes)
		(effects
			(font
				(size 1.27 1.27)
			)
			(justify left bottom)
		)
	)
	(global_label "12V0_MOLEX"
		(shape input)
		(at 210.82 262.89 180)
		(fields_autoplaced yes)
		(effects
			(font
				(size 1.27 1.27)
			)
			(justify right)
		)
		(property "Intersheetrefs" "${INTERSHEET_REFS}"
			(at 196.5536 262.9694 0)
			(effects
				(font
					(size 1.27 1.27)
				)
				(justify right)
				(hide yes)
			)
		)
	)
	(global_label "12V0_DCDC"
		(shape input)
		(at 222.25 300.99 180)
		(fields_autoplaced yes)
		(effects
			(font
				(size 1.27 1.27)
			)
			(justify right)
		)
		(property "Intersheetrefs" "${INTERSHEET_REFS}"
			(at 209.0721 301.0694 0)
			(effects
				(font
					(size 1.27 1.27)
				)
				(justify right)
				(hide yes)
			)
		)
	)
	(global_label "3V3_PGOOD"
		(shape input)
		(at 121.92 369.57 0)
		(fields_autoplaced yes)
		(effects
			(font
				(size 1.27 1.27)
			)
			(justify left)
		)
		(property "Intersheetrefs" "${INTERSHEET_REFS}"
			(at 135.2793 369.4906 0)
			(effects
				(font
					(size 1.27 1.27)
				)
				(justify left)
				(hide yes)
			)
		)
	)
	(global_label "SPI_CS"
		(shape input)
		(at 62.23 125.73 180)
		(fields_autoplaced yes)
		(effects
			(font
				(size 1.27 1.27)
			)
			(justify right)
		)
		(property "Intersheetrefs" "${INTERSHEET_REFS}"
			(at 53.2855 125.6506 0)
			(effects
				(font
					(size 1.27 1.27)
				)
				(justify right)
				(hide yes)
			)
		)
	)
	(global_label "SPI_MISO"
		(shape input)
		(at 62.23 123.19 180)
		(fields_autoplaced yes)
		(effects
			(font
				(size 1.27 1.27)
			)
			(justify right)
		)
		(property "Intersheetrefs" "${INTERSHEET_REFS}"
			(at 51.1688 123.1106 0)
			(effects
				(font
					(size 1.27 1.27)
				)
				(justify right)
				(hide yes)
			)
		)
	)
	(global_label "3V3_SYS"
		(shape input)
		(at 195.58 113.03 180)
		(fields_autoplaced yes)
		(effects
			(font
				(size 1.27 1.27)
			)
			(justify right)
		)
		(property "Intersheetrefs" "${INTERSHEET_REFS}"
			(at 185.184 113.1094 0)
			(effects
				(font
					(size 1.27 1.27)
				)
				(justify right)
				(hide yes)
			)
		)
	)
	(global_label "SBU1"
		(shape input)
		(at 139.7 105.41 0)
		(fields_autoplaced yes)
		(effects
			(font
				(size 1.27 1.27)
			)
			(justify left)
		)
		(property "Intersheetrefs" "${INTERSHEET_REFS}"
			(at 147.1326 105.3306 0)
			(effects
				(font
					(size 1.27 1.27)
				)
				(justify left)
				(hide yes)
			)
		)
	)
	(global_label "12V0_PGOOD"
		(shape input)
		(at 114.3 218.44 180)
		(fields_autoplaced yes)
		(effects
			(font
				(size 1.27 1.27)
			)
			(justify right)
		)
		(property "Intersheetrefs" "${INTERSHEET_REFS}"
			(at 99.7312 218.3606 0)
			(effects
				(font
					(size 1.27 1.27)
				)
				(justify right)
				(hide yes)
			)
		)
	)
	(global_label "3V3_PCIE"
		(shape input)
		(at 265.43 118.11 0)
		(fields_autoplaced yes)
		(effects
			(font
				(size 1.27 1.27)
			)
			(justify left)
		)
		(property "Intersheetrefs" "${INTERSHEET_REFS}"
			(at 276.6121 118.0306 0)
			(effects
				(font
					(size 1.27 1.27)
				)
				(justify left)
				(hide yes)
			)
		)
	)
	(global_label "USB_T_P"
		(shape input)
		(at 139.7 90.17 0)
		(fields_autoplaced yes)
		(effects
			(font
				(size 1.27 1.27)
			)
			(justify left)
		)
		(property "Intersheetrefs" "${INTERSHEET_REFS}"
			(at 150.096 90.0906 0)
			(effects
				(font
					(size 1.27 1.27)
				)
				(justify left)
				(hide yes)
			)
		)
	)
	(global_label "12V0_MOLEX"
		(shape input)
		(at 45.72 260.35 180)
		(fields_autoplaced yes)
		(effects
			(font
				(size 1.27 1.27)
			)
			(justify right)
		)
		(property "Intersheetrefs" "${INTERSHEET_REFS}"
			(at 31.4536 260.4294 0)
			(effects
				(font
					(size 1.27 1.27)
				)
				(justify right)
				(hide yes)
			)
		)
	)
	(global_label "LSX_R2P"
		(shape input)
		(at 71.12 146.05 180)
		(fields_autoplaced yes)
		(effects
			(font
				(size 1.27 1.27)
			)
			(justify right)
		)
		(property "Intersheetrefs" "${INTERSHEET_REFS}"
			(at 60.5426 145.9706 0)
			(effects
				(font
					(size 1.27 1.27)
				)
				(justify right)
				(hide yes)
			)
		)
	)
	(global_label "5V0_USB"
		(shape input)
		(at 24.13 198.12 180)
		(fields_autoplaced yes)
		(effects
			(font
				(size 1.27 1.27)
			)
			(justify right)
		)
		(property "Intersheetrefs" "${INTERSHEET_REFS}"
			(at 13.4317 198.0406 0)
			(effects
				(font
					(size 1.27 1.27)
				)
				(justify right)
				(hide yes)
			)
		)
	)
	(global_label "3V3_SYS"
		(shape input)
		(at 43.18 58.42 180)
		(fields_autoplaced yes)
		(effects
			(font
				(size 1.27 1.27)
			)
			(justify right)
		)
		(property "Intersheetrefs" "${INTERSHEET_REFS}"
			(at 32.784 58.4994 0)
			(effects
				(font
					(size 1.27 1.27)
				)
				(justify right)
				(hide yes)
			)
		)
	)
	(global_label "0P9_BUFFERED"
		(shape input)
		(at 194.31 129.54 180)
		(fields_autoplaced yes)
		(effects
			(font
				(size 1.27 1.27)
			)
			(justify right)
		)
		(property "Intersheetrefs" "${INTERSHEET_REFS}"
			(at 177.6245 129.4606 0)
			(effects
				(font
					(size 1.27 1.27)
				)
				(justify right)
				(hide yes)
			)
		)
	)
	(global_label "12V0_SYS"
		(shape input)
		(at 30.48 384.81 180)
		(fields_autoplaced yes)
		(effects
			(font
				(size 1.27 1.27)
			)
			(justify right)
		)
		(property "Intersheetrefs" "${INTERSHEET_REFS}"
			(at 18.8745 384.8894 0)
			(effects
				(font
					(size 1.27 1.27)
				)
				(justify right)
				(hide yes)
			)
		)
	)
	(global_label "SPI_SCLK"
		(shape input)
		(at 62.23 118.11 180)
		(fields_autoplaced yes)
		(effects
			(font
				(size 1.27 1.27)
			)
			(justify right)
		)
		(property "Intersheetrefs" "${INTERSHEET_REFS}"
			(at 50.9874 118.0306 0)
			(effects
				(font
					(size 1.27 1.27)
				)
				(justify right)
				(hide yes)
			)
		)
	)
	(global_label "5V0_USB"
		(shape input)
		(at 196.85 46.99 0)
		(fields_autoplaced yes)
		(effects
			(font
				(size 1.27 1.27)
			)
			(justify left)
		)
		(property "Intersheetrefs" "${INTERSHEET_REFS}"
			(at 207.5483 47.0694 0)
			(effects
				(font
					(size 1.27 1.27)
				)
				(justify left)
				(hide yes)
			)
		)
	)
	(global_label "USB_RP_N"
		(shape input)
		(at 71.12 163.83 180)
		(fields_autoplaced yes)
		(effects
			(font
				(size 1.27 1.27)
			)
			(justify right)
		)
		(property "Intersheetrefs" "${INTERSHEET_REFS}"
			(at 59.0912 163.7506 0)
			(effects
				(font
					(size 1.27 1.27)
				)
				(justify right)
				(hide yes)
			)
		)
	)
	(global_label "CC1"
		(shape input)
		(at 184.15 74.93 0)
		(fields_autoplaced yes)
		(effects
			(font
				(size 1.27 1.27)
			)
			(justify left)
		)
		(property "Intersheetrefs" "${INTERSHEET_REFS}"
			(at 190.3126 74.8506 0)
			(effects
				(font
					(size 1.27 1.27)
				)
				(justify left)
				(hide yes)
			)
		)
	)
	(global_label "USB_RP_P"
		(shape input)
		(at 71.12 161.29 180)
		(fields_autoplaced yes)
		(effects
			(font
				(size 1.27 1.27)
			)
			(justify right)
		)
		(property "Intersheetrefs" "${INTERSHEET_REFS}"
			(at 59.1517 161.2106 0)
			(effects
				(font
					(size 1.27 1.27)
				)
				(justify right)
				(hide yes)
			)
		)
	)
	(global_label "0P9_BUFFERED"
		(shape input)
		(at 219.71 80.01 180)
		(fields_autoplaced yes)
		(effects
			(font
				(size 1.27 1.27)
			)
			(justify right)
		)
		(property "Intersheetrefs" "${INTERSHEET_REFS}"
			(at 203.0245 79.9306 0)
			(effects
				(font
					(size 1.27 1.27)
				)
				(justify right)
				(hide yes)
			)
		)
	)
	(global_label "3V3_SYS"
		(shape input)
		(at 241.3 346.71 0)
		(fields_autoplaced yes)
		(effects
			(font
				(size 1.27 1.27)
			)
			(justify left)
		)
		(property "Intersheetrefs" "${INTERSHEET_REFS}"
			(at 251.696 346.6306 0)
			(effects
				(font
					(size 1.27 1.27)
				)
				(justify left)
				(hide yes)
			)
		)
	)
	(global_label "12V0_DCDC"
		(shape input)
		(at 270.51 203.2 0)
		(fields_autoplaced yes)
		(effects
			(font
				(size 1.27 1.27)
			)
			(justify left)
		)
		(property "Intersheetrefs" "${INTERSHEET_REFS}"
			(at 283.6879 203.1206 0)
			(effects
				(font
					(size 1.27 1.27)
				)
				(justify left)
				(hide yes)
			)
		)
	)
	(global_label "3V3_PCIE"
		(shape input)
		(at 218.44 88.9 180)
		(fields_autoplaced yes)
		(effects
			(font
				(size 1.27 1.27)
			)
			(justify right)
		)
		(property "Intersheetrefs" "${INTERSHEET_REFS}"
			(at 207.2579 88.9794 0)
			(effects
				(font
					(size 1.27 1.27)
				)
				(justify right)
				(hide yes)
			)
		)
	)
	(global_label "SPI_MOSI"
		(shape input)
		(at 62.23 120.65 180)
		(fields_autoplaced yes)
		(effects
			(font
				(size 1.27 1.27)
			)
			(justify right)
		)
		(property "Intersheetrefs" "${INTERSHEET_REFS}"
			(at 51.1688 120.5706 0)
			(effects
				(font
					(size 1.27 1.27)
				)
				(justify right)
				(hide yes)
			)
		)
	)
	(global_label "SBU2"
		(shape input)
		(at 139.7 107.95 0)
		(fields_autoplaced yes)
		(effects
			(font
				(size 1.27 1.27)
			)
			(justify left)
		)
		(property "Intersheetrefs" "${INTERSHEET_REFS}"
			(at 147.1326 107.8706 0)
			(effects
				(font
					(size 1.27 1.27)
				)
				(justify left)
				(hide yes)
			)
		)
	)
	(global_label "3V3_SYS"
		(shape input)
		(at 25.4 60.96 180)
		(fields_autoplaced yes)
		(effects
			(font
				(size 1.27 1.27)
			)
			(justify right)
		)
		(property "Intersheetrefs" "${INTERSHEET_REFS}"
			(at 15.004 61.0394 0)
			(effects
				(font
					(size 1.27 1.27)
				)
				(justify right)
				(hide yes)
			)
		)
	)
	(global_label "I2C1_SCL"
		(shape input)
		(at 26.67 74.93 180)
		(fields_autoplaced yes)
		(effects
			(font
				(size 1.27 1.27)
			)
			(justify right)
		)
		(property "Intersheetrefs" "${INTERSHEET_REFS}"
			(at 15.4879 74.8506 0)
			(effects
				(font
					(size 1.27 1.27)
				)
				(justify right)
				(hide yes)
			)
		)
	)
	(global_label "3V3_PCIE_AUX"
		(shape input)
		(at 241.3 161.29 0)
		(fields_autoplaced yes)
		(effects
			(font
				(size 1.27 1.27)
			)
			(justify left)
		)
		(property "Intersheetrefs" "${INTERSHEET_REFS}"
			(at 257.0783 161.2106 0)
			(effects
				(font
					(size 1.27 1.27)
				)
				(justify left)
				(hide yes)
			)
		)
	)
	(global_label "I2C1_SDA"
		(shape input)
		(at 26.67 72.39 180)
		(fields_autoplaced yes)
		(effects
			(font
				(size 1.27 1.27)
			)
			(justify right)
		)
		(property "Intersheetrefs" "${INTERSHEET_REFS}"
			(at 15.4274 72.3106 0)
			(effects
				(font
					(size 1.27 1.27)
				)
				(justify right)
				(hide yes)
			)
		)
	)
	(global_label "3V3_SYS"
		(shape input)
		(at 218.44 161.29 180)
		(fields_autoplaced yes)
		(effects
			(font
				(size 1.27 1.27)
			)
			(justify right)
		)
		(property "Intersheetrefs" "${INTERSHEET_REFS}"
			(at 208.044 161.3694 0)
			(effects
				(font
					(size 1.27 1.27)
				)
				(justify right)
				(hide yes)
			)
		)
	)
	(global_label "5V0_USB"
		(shape input)
		(at 24.13 330.2 180)
		(fields_autoplaced yes)
		(effects
			(font
				(size 1.27 1.27)
			)
			(justify right)
		)
		(property "Intersheetrefs" "${INTERSHEET_REFS}"
			(at 13.4317 330.1206 0)
			(effects
				(font
					(size 1.27 1.27)
				)
				(justify right)
				(hide yes)
			)
		)
	)
	(global_label "CC2"
		(shape input)
		(at 184.15 77.47 0)
		(fields_autoplaced yes)
		(effects
			(font
				(size 1.27 1.27)
			)
			(justify left)
		)
		(property "Intersheetrefs" "${INTERSHEET_REFS}"
			(at 190.3126 77.3906 0)
			(effects
				(font
					(size 1.27 1.27)
				)
				(justify left)
				(hide yes)
			)
		)
	)
	(global_label "3V3_FAN_CTRL"
		(shape input)
		(at 118.11 384.81 0)
		(fields_autoplaced yes)
		(effects
			(font
				(size 1.27 1.27)
			)
			(justify left)
		)
		(property "Intersheetrefs" "${INTERSHEET_REFS}"
			(at 134.0093 384.8894 0)
			(effects
				(font
					(size 1.27 1.27)
				)
				(justify left)
				(hide yes)
			)
		)
	)
	(global_label "12V0_PCIE"
		(shape input)
		(at 261.62 62.23 0)
		(fields_autoplaced yes)
		(effects
			(font
				(size 1.27 1.27)
			)
			(justify left)
		)
		(property "Intersheetrefs" "${INTERSHEET_REFS}"
			(at 274.0117 62.3094 0)
			(effects
				(font
					(size 1.27 1.27)
				)
				(justify left)
				(hide yes)
			)
		)
	)
	(global_label "USB_B_N"
		(shape input)
		(at 139.7 100.33 0)
		(fields_autoplaced yes)
		(effects
			(font
				(size 1.27 1.27)
			)
			(justify left)
		)
		(property "Intersheetrefs" "${INTERSHEET_REFS}"
			(at 150.4588 100.4094 0)
			(effects
				(font
					(size 1.27 1.27)
				)
				(justify left)
				(hide yes)
			)
		)
	)
	(global_label "12V0_SYS"
		(shape input)
		(at 270.51 300.99 0)
		(fields_autoplaced yes)
		(effects
			(font
				(size 1.27 1.27)
			)
			(justify left)
		)
		(property "Intersheetrefs" "${INTERSHEET_REFS}"
			(at 282.1155 300.9106 0)
			(effects
				(font
					(size 1.27 1.27)
				)
				(justify left)
				(hide yes)
			)
		)
	)
	(global_label "HPD"
		(shape input)
		(at 39.37 102.87 180)
		(fields_autoplaced yes)
		(effects
			(font
				(size 1.27 1.27)
			)
			(justify right)
		)
		(property "Intersheetrefs" "${INTERSHEET_REFS}"
			(at 33.0864 102.7906 0)
			(effects
				(font
					(size 1.27 1.27)
				)
				(justify right)
				(hide yes)
			)
		)
	)
	(global_label "AUX_P"
		(shape input)
		(at 45.72 148.59 180)
		(fields_autoplaced yes)
		(effects
			(font
				(size 1.27 1.27)
			)
			(justify right)
		)
		(property "Intersheetrefs" "${INTERSHEET_REFS}"
			(at 37.4407 148.5106 0)
			(effects
				(font
					(size 1.27 1.27)
				)
				(justify right)
				(hide yes)
			)
		)
	)
	(global_label "12V0_SYS"
		(shape input)
		(at 269.24 262.89 0)
		(fields_autoplaced yes)
		(effects
			(font
				(size 1.27 1.27)
			)
			(justify left)
		)
		(property "Intersheetrefs" "${INTERSHEET_REFS}"
			(at 280.8455 262.8106 0)
			(effects
				(font
					(size 1.27 1.27)
				)
				(justify left)
				(hide yes)
			)
		)
	)
	(global_label "AUX_N"
		(shape input)
		(at 45.72 144.78 180)
		(fields_autoplaced yes)
		(effects
			(font
				(size 1.27 1.27)
			)
			(justify right)
		)
		(property "Intersheetrefs" "${INTERSHEET_REFS}"
			(at 37.3802 144.7006 0)
			(effects
				(font
					(size 1.27 1.27)
				)
				(justify right)
				(hide yes)
			)
		)
	)
	(global_label "RESET_N"
		(shape input)
		(at 167.64 138.43 0)
		(fields_autoplaced yes)
		(effects
			(font
				(size 1.27 1.27)
			)
			(justify left)
		)
		(property "Intersheetrefs" "${INTERSHEET_REFS}"
			(at 178.0964 138.3506 0)
			(effects
				(font
					(size 1.27 1.27)
				)
				(justify left)
				(hide yes)
			)
		)
	)
	(global_label "3V3_SYS"
		(shape input)
		(at 25.4 29.21 0)
		(fields_autoplaced yes)
		(effects
			(font
				(size 1.27 1.27)
			)
			(justify left)
		)
		(property "Intersheetrefs" "${INTERSHEET_REFS}"
			(at 35.796 29.1306 0)
			(effects
				(font
					(size 1.27 1.27)
				)
				(justify left)
				(hide yes)
			)
		)
	)
	(global_label "12V0_MOLEX"
		(shape input)
		(at 45.72 242.57 180)
		(fields_autoplaced yes)
		(effects
			(font
				(size 1.27 1.27)
			)
			(justify right)
		)
		(property "Intersheetrefs" "${INTERSHEET_REFS}"
			(at 31.4536 242.6494 0)
			(effects
				(font
					(size 1.27 1.27)
				)
				(justify right)
				(hide yes)
			)
		)
	)
	(global_label "USB_T_N"
		(shape input)
		(at 139.7 92.71 0)
		(fields_autoplaced yes)
		(effects
			(font
				(size 1.27 1.27)
			)
			(justify left)
		)
		(property "Intersheetrefs" "${INTERSHEET_REFS}"
			(at 150.1564 92.6306 0)
			(effects
				(font
					(size 1.27 1.27)
				)
				(justify left)
				(hide yes)
			)
		)
	)
	(global_label "USB_B_P"
		(shape input)
		(at 139.7 97.79 0)
		(fields_autoplaced yes)
		(effects
			(font
				(size 1.27 1.27)
			)
			(justify left)
		)
		(property "Intersheetrefs" "${INTERSHEET_REFS}"
			(at 150.3983 97.8694 0)
			(effects
				(font
					(size 1.27 1.27)
				)
				(justify left)
				(hide yes)
			)
		)
	)
	(global_label "I2C1_IRQ"
		(shape input)
		(at 26.67 77.47 180)
		(fields_autoplaced yes)
		(effects
			(font
				(size 1.27 1.27)
			)
			(justify right)
		)
		(property "Intersheetrefs" "${INTERSHEET_REFS}"
			(at 15.7902 77.3906 0)
			(effects
				(font
					(size 1.27 1.27)
				)
				(justify right)
				(hide yes)
			)
		)
	)
	(global_label "LSX_P2R"
		(shape input)
		(at 71.12 148.59 180)
		(fields_autoplaced yes)
		(effects
			(font
				(size 1.27 1.27)
			)
			(justify right)
		)
		(property "Intersheetrefs" "${INTERSHEET_REFS}"
			(at 60.5426 148.5106 0)
			(effects
				(font
					(size 1.27 1.27)
				)
				(justify right)
				(hide yes)
			)
		)
	)
	(global_label "12V0_SYS"
		(shape input)
		(at 223.52 62.23 180)
		(fields_autoplaced yes)
		(effects
			(font
				(size 1.27 1.27)
			)
			(justify right)
		)
		(property "Intersheetrefs" "${INTERSHEET_REFS}"
			(at 211.9145 62.3094 0)
			(effects
				(font
					(size 1.27 1.27)
				)
				(justify right)
				(hide yes)
			)
		)
	)
	(symbol
		(lib_id "antmicropower:GND")
		(at 148.59 133.35 0)
		(unit 1)
		(exclude_from_sim no)
		(in_bom yes)
		(on_board yes)
		(dnp no)
		(property "Reference" "#PWR055"
			(at 148.59 139.7 0)
			(effects
				(font
					(size 1.27 1.27)
				)
				(hide yes)
			)
		)
		(property "Value" "GND"
			(at 148.59 137.16 0)
			(effects
				(font
					(size 1.27 1.27)
				)
			)
		)
		(property "Footprint" ""
			(at 148.59 133.35 0)
			(effects
				(font
					(size 1.27 1.27)
				)
				(hide yes)
			)
		)
		(property "Datasheet" ""
			(at 148.59 133.35 0)
			(effects
				(font
					(size 1.27 1.27)
				)
				(hide yes)
			)
		)
		(property "Description" ""
			(at 148.59 133.35 0)
			(effects
				(font
					(size 1.27 1.27)
				)
				(hide yes)
			)
		)
		(property "Author" "Antmicro"
			(at 157.48 140.97 0)
			(effects
				(font
					(size 1.27 1.27)
					(thickness 0.15)
				)
				(justify left bottom)
				(hide yes)
			)
		)
		(property "License" "Apache-2.0"
			(at 157.48 143.51 0)
			(effects
				(font
					(size 1.27 1.27)
					(thickness 0.15)
				)
				(justify left bottom)
				(hide yes)
			)
		)
		(pin "1"
		)
		(instances
			(project "thunderbolt-gpu-adapter"
				(path ""
					(reference "#PWR055")
					(unit 1)
				)
			)
		)
	)
	(symbol
		(lib_id "antmicroCapacitors0402:C_1u_0402")
		(at 133.35 49.53 0)
		(unit 1)
		(exclude_from_sim no)
		(in_bom yes)
		(on_board yes)
		(dnp no)
		(property "Reference" "C34"
			(at 138.43 48.26 0)
			(effects
				(font
					(size 1.27 1.27)
					(thickness 0.15)
				)
			)
		)
		(property "Value" "C_1u_0402"
			(at 153.67 59.69 0)
			(effects
				(font
					(size 1.27 1.27)
					(thickness 0.15)
				)
				(justify left bottom)
				(hide yes)
			)
		)
		(property "Footprint" "antmicro-footprints:C_0402_1005Metric"
			(at 153.67 62.23 0)
			(effects
				(font
					(size 1.27 1.27)
					(thickness 0.15)
				)
				(justify left bottom)
				(hide yes)
			)
		)
		(property "Datasheet" "https://product.tdk.com/en/search/capacitor/ceramic/mlcc/info?part_no=C1005X6S1A105K050BC"
			(at 153.67 64.77 0)
			(effects
				(font
					(size 1.27 1.27)
					(thickness 0.15)
				)
				(justify left bottom)
				(hide yes)
			)
		)
		(property "Description" ""
			(at 133.35 49.53 0)
			(effects
				(font
					(size 1.27 1.27)
				)
				(hide yes)
			)
		)
		(property "MPN" "C1005X6S1A105K050BC"
			(at 153.67 67.31 0)
			(effects
				(font
					(size 1.27 1.27)
					(thickness 0.15)
				)
				(justify left bottom)
				(hide yes)
			)
		)
		(property "Manufacturer" "TDK"
			(at 153.67 69.85 0)
			(effects
				(font
					(size 1.27 1.27)
					(thickness 0.15)
				)
				(justify left bottom)
				(hide yes)
			)
		)
		(property "License" "Apache-2.0"
			(at 153.67 72.39 0)
			(effects
				(font
					(size 1.27 1.27)
					(thickness 0.15)
				)
				(justify left bottom)
				(hide yes)
			)
		)
		(property "Val" "1u"
			(at 137.795 50.8 0)
			(effects
				(font
					(size 1.27 1.27)
					(thickness 0.15)
				)
			)
		)
		(property "Voltage" ""
			(at 153.67 77.47 0)
			(effects
				(font
					(size 1.27 1.27)
				)
				(justify left bottom)
				(hide yes)
			)
		)
		(property "Dielectric" ""
			(at 153.67 80.01 0)
			(effects
				(font
					(size 1.27 1.27)
				)
				(justify left bottom)
				(hide yes)
			)
		)
		(property "Author" "Antmicro"
			(at 153.67 74.93 0)
			(effects
				(font
					(size 1.27 1.27)
					(thickness 0.15)
				)
				(justify left bottom)
				(hide yes)
			)
		)
		(pin "1"
		)
		(pin "2"
		)
		(instances
			(project "thunderbolt-gpu-adapter"
				(path ""
					(reference "C34")
					(unit 1)
				)
			)
		)
	)
	(symbol
		(lib_id "antmicroResistors0402:R_0R_0402")
		(at 227.33 161.29 0)
		(unit 1)
		(exclude_from_sim no)
		(in_bom yes)
		(on_board yes)
		(dnp no)
		(property "Reference" "R123"
			(at 229.87 159.385 0)
			(effects
				(font
					(size 1.27 1.27)
					(thickness 0.15)
				)
			)
		)
		(property "Value" "R_0R_0402"
			(at 247.65 173.99 0)
			(effects
				(font
					(size 1.27 1.27)
					(thickness 0.15)
				)
				(justify left bottom)
				(hide yes)
			)
		)
		(property "Footprint" "antmicro-footprints:R_0402_1005Metric"
			(at 247.65 176.53 0)
			(effects
				(font
					(size 1.27 1.27)
					(thickness 0.15)
				)
				(justify left bottom)
				(hide yes)
			)
		)
		(property "Datasheet" "https://industrial.panasonic.com/cdbs/www-data/pdf/RDA0000/AOA0000C301.pdf"
			(at 247.65 179.07 0)
			(effects
				(font
					(size 1.27 1.27)
					(thickness 0.15)
				)
				(justify left bottom)
				(hide yes)
			)
		)
		(property "Description" ""
			(at 227.33 161.29 0)
			(effects
				(font
					(size 1.27 1.27)
				)
				(hide yes)
			)
		)
		(property "MPN" "ERJ2GE0R00X"
			(at 247.65 181.61 0)
			(effects
				(font
					(size 1.27 1.27)
					(thickness 0.15)
				)
				(justify left bottom)
				(hide yes)
			)
		)
		(property "Manufacturer" "Panasonic"
			(at 247.65 184.15 0)
			(effects
				(font
					(size 1.27 1.27)
					(thickness 0.15)
				)
				(justify left bottom)
				(hide yes)
			)
		)
		(property "License" "Apache-2.0"
			(at 247.65 186.69 0)
			(effects
				(font
					(size 1.27 1.27)
					(thickness 0.15)
				)
				(justify left bottom)
				(hide yes)
			)
		)
		(property "Val" "0R"
			(at 229.87 161.29 0)
			(effects
				(font
					(size 1.27 1.27)
					(thickness 0.15)
				)
			)
		)
		(property "Tolerance" "~"
			(at 247.65 171.45 0)
			(effects
				(font
					(size 1.27 1.27)
				)
				(justify left bottom)
				(hide yes)
			)
		)
		(property "Current" "1A"
			(at 229.87 157.48 0)
			(effects
				(font
					(size 1.27 1.27)
					(thickness 0.15)
				)
				(hide yes)
			)
		)
		(property "Author" "Antmicro"
			(at 247.65 189.23 0)
			(effects
				(font
					(size 1.27 1.27)
					(thickness 0.15)
				)
				(justify left bottom)
				(hide yes)
			)
		)
		(pin "1"
		)
		(pin "2"
		)
		(instances
			(project "thunderbolt-gpu-adapter"
				(path ""
					(reference "R123")
					(unit 1)
				)
			)
		)
	)
	(symbol
		(lib_id "antmicroResistors0402:R_1M_0402")
		(at 64.77 138.43 0)
		(unit 1)
		(exclude_from_sim no)
		(in_bom yes)
		(on_board yes)
		(dnp no)
		(fields_autoplaced yes)
		(property "Reference" "R21"
			(at 67.31 132.08 0)
			(effects
				(font
					(size 1.27 1.27)
					(thickness 0.15)
				)
			)
		)
		(property "Value" "R_1M_0402"
			(at 85.09 151.13 0)
			(effects
				(font
					(size 1.27 1.27)
					(thickness 0.15)
				)
				(justify left bottom)
				(hide yes)
			)
		)
		(property "Footprint" "antmicro-footprints:R_0402_1005Metric"
			(at 85.09 153.67 0)
			(effects
				(font
					(size 1.27 1.27)
					(thickness 0.15)
				)
				(justify left bottom)
				(hide yes)
			)
		)
		(property "Datasheet" "https://www.bourns.com/docs/product-datasheets/cr.pdf"
			(at 85.09 156.21 0)
			(effects
				(font
					(size 1.27 1.27)
					(thickness 0.15)
				)
				(justify left bottom)
				(hide yes)
			)
		)
		(property "Description" ""
			(at 64.77 138.43 0)
			(effects
				(font
					(size 1.27 1.27)
				)
				(hide yes)
			)
		)
		(property "MPN" "CR0402-FX-1004GLF"
			(at 85.09 158.75 0)
			(effects
				(font
					(size 1.27 1.27)
					(thickness 0.15)
				)
				(justify left bottom)
				(hide yes)
			)
		)
		(property "Manufacturer" "Bourns"
			(at 85.09 161.29 0)
			(effects
				(font
					(size 1.27 1.27)
					(thickness 0.15)
				)
				(justify left bottom)
				(hide yes)
			)
		)
		(property "License" "Apache-2.0"
			(at 85.09 163.83 0)
			(effects
				(font
					(size 1.27 1.27)
					(thickness 0.15)
				)
				(justify left bottom)
				(hide yes)
			)
		)
		(property "Val" "1M"
			(at 67.31 134.62 0)
			(effects
				(font
					(size 1.27 1.27)
					(thickness 0.15)
				)
			)
		)
		(property "Tolerance" "1%"
			(at 85.09 148.59 0)
			(effects
				(font
					(size 1.27 1.27)
				)
				(justify left bottom)
				(hide yes)
			)
		)
		(property "Author" "Antmicro"
			(at 85.09 166.37 0)
			(effects
				(font
					(size 1.27 1.27)
					(thickness 0.15)
				)
				(justify left bottom)
				(hide yes)
			)
		)
		(pin "1"
		)
		(pin "2"
		)
		(instances
			(project "thunderbolt-gpu-adapter"
				(path ""
					(reference "R21")
					(unit 1)
				)
			)
		)
	)
	(symbol
		(lib_id "antmicropower:GND")
		(at 83.82 340.36 0)
		(unit 1)
		(exclude_from_sim no)
		(in_bom yes)
		(on_board yes)
		(dnp no)
		(property "Reference" "#PWR027"
			(at 83.82 346.71 0)
			(effects
				(font
					(size 1.27 1.27)
				)
				(hide yes)
			)
		)
		(property "Value" "GND"
			(at 83.82 344.17 0)
			(effects
				(font
					(size 1.27 1.27)
				)
			)
		)
		(property "Footprint" ""
			(at 83.82 340.36 0)
			(effects
				(font
					(size 1.27 1.27)
				)
				(hide yes)
			)
		)
		(property "Datasheet" ""
			(at 83.82 340.36 0)
			(effects
				(font
					(size 1.27 1.27)
				)
				(hide yes)
			)
		)
		(property "Description" ""
			(at 83.82 340.36 0)
			(effects
				(font
					(size 1.27 1.27)
				)
				(hide yes)
			)
		)
		(property "Author" "Antmicro"
			(at 92.71 347.98 0)
			(effects
				(font
					(size 1.27 1.27)
					(thickness 0.15)
				)
				(justify left bottom)
				(hide yes)
			)
		)
		(property "License" "Apache-2.0"
			(at 92.71 350.52 0)
			(effects
				(font
					(size 1.27 1.27)
					(thickness 0.15)
				)
				(justify left bottom)
				(hide yes)
			)
		)
		(pin "1"
		)
		(instances
			(project "thunderbolt-gpu-adapter"
				(path ""
					(reference "#PWR027")
					(unit 1)
				)
			)
		)
	)
	(symbol
		(lib_id "antmicroResistors0402:R_100k_0402")
		(at 214.63 119.38 90)
		(unit 1)
		(exclude_from_sim no)
		(in_bom yes)
		(on_board yes)
		(dnp no)
		(property "Reference" "R124"
			(at 216.535 115.57 90)
			(effects
				(font
					(size 1.27 1.27)
					(thickness 0.15)
				)
				(justify right)
			)
		)
		(property "Value" "R_100k_0402"
			(at 227.33 99.06 0)
			(effects
				(font
					(size 1.27 1.27)
					(thickness 0.15)
				)
				(justify left bottom)
				(hide yes)
			)
		)
		(property "Footprint" "antmicro-footprints:R_0402_1005Metric"
			(at 229.87 99.06 0)
			(effects
				(font
					(size 1.27 1.27)
					(thickness 0.15)
				)
				(justify left bottom)
				(hide yes)
			)
		)
		(property "Datasheet" "https://www.bourns.com/docs/product-datasheets/cr.pdf"
			(at 232.41 99.06 0)
			(effects
				(font
					(size 1.27 1.27)
					(thickness 0.15)
				)
				(justify left bottom)
				(hide yes)
			)
		)
		(property "Description" ""
			(at 214.63 119.38 0)
			(effects
				(font
					(size 1.27 1.27)
				)
				(hide yes)
			)
		)
		(property "MPN" "CR0402-FX-1003GLF"
			(at 234.95 99.06 0)
			(effects
				(font
					(size 1.27 1.27)
					(thickness 0.15)
				)
				(justify left bottom)
				(hide yes)
			)
		)
		(property "Manufacturer" "Bourns"
			(at 237.49 99.06 0)
			(effects
				(font
					(size 1.27 1.27)
					(thickness 0.15)
				)
				(justify left bottom)
				(hide yes)
			)
		)
		(property "License" "Apache-2.0"
			(at 240.03 99.06 0)
			(effects
				(font
					(size 1.27 1.27)
					(thickness 0.15)
				)
				(justify left bottom)
				(hide yes)
			)
		)
		(property "Author" "Antmicro"
			(at 242.57 99.06 0)
			(effects
				(font
					(size 1.27 1.27)
					(thickness 0.15)
				)
				(justify left bottom)
				(hide yes)
			)
		)
		(property "Val" "100k"
			(at 216.535 118.11 90)
			(effects
				(font
					(size 1.27 1.27)
					(thickness 0.15)
				)
				(justify right)
			)
		)
		(property "Tolerance" "1%"
			(at 224.79 99.06 0)
			(effects
				(font
					(size 1.27 1.27)
				)
				(justify left bottom)
				(hide yes)
			)
		)
		(pin "1"
		)
		(pin "2"
		)
		(instances
			(project "thunderbolt-gpu-adapter"
				(path ""
					(reference "R124")
					(unit 1)
				)
			)
		)
	)
	(symbol
		(lib_id "antmicroDCDCConverters:MP2386GG")
		(at 101.6 344.17 0)
		(unit 1)
		(exclude_from_sim no)
		(in_bom yes)
		(on_board yes)
		(dnp no)
		(fields_autoplaced yes)
		(property "Reference" "U2"
			(at 110.49 336.55 0)
			(effects
				(font
					(size 1.27 1.27)
					(thickness 0.15)
				)
			)
		)
		(property "Value" "MP2386GG"
			(at 134.62 351.79 0)
			(effects
				(font
					(size 1.27 1.27)
					(thickness 0.15)
				)
				(justify left bottom)
				(hide yes)
			)
		)
		(property "Footprint" "antmicro-footprints:QFN-11_2x2mm_P0.5mm"
			(at 134.62 354.33 0)
			(effects
				(font
					(size 1.27 1.27)
					(thickness 0.15)
				)
				(justify left bottom)
				(hide yes)
			)
		)
		(property "Datasheet" "https://www.monolithicpower.com/en/documentview/productdocument/index/version/2/document_type/Datasheet/lang/en/sku/MP2386GG-Z/document_id/4066/"
			(at 134.62 356.87 0)
			(effects
				(font
					(size 1.27 1.27)
					(thickness 0.15)
				)
				(justify left bottom)
				(hide yes)
			)
		)
		(property "Description" ""
			(at 101.6 344.17 0)
			(effects
				(font
					(size 1.27 1.27)
				)
				(hide yes)
			)
		)
		(property "Manufacturer" "Monolithic Power Systems"
			(at 134.62 359.41 0)
			(effects
				(font
					(size 1.27 1.27)
					(thickness 0.15)
				)
				(justify left bottom)
				(hide yes)
			)
		)
		(property "MPN" "MP2386GG-P"
			(at 110.49 339.09 0)
			(effects
				(font
					(size 1.27 1.27)
					(thickness 0.15)
				)
			)
		)
		(property "License" "Apache-2.0"
			(at 134.62 367.03 0)
			(effects
				(font
					(size 1.27 1.27)
					(thickness 0.15)
				)
				(justify left bottom)
				(hide yes)
			)
		)
		(property "Author" "Antmicro"
			(at 134.62 364.49 0)
			(effects
				(font
					(size 1.27 1.27)
					(thickness 0.15)
				)
				(justify left bottom)
				(hide yes)
			)
		)
		(pin "1"
		)
		(pin "10"
		)
		(pin "11"
		)
		(pin "2"
		)
		(pin "3"
		)
		(pin "4"
		)
		(pin "5"
		)
		(pin "6"
		)
		(pin "7"
		)
		(pin "8"
		)
		(pin "9"
		)
		(instances
			(project "thunderbolt-gpu-adapter"
				(path ""
					(reference "U2")
					(unit 1)
				)
			)
		)
	)
	(symbol
		(lib_id "antmicroTestPoints:TP_1mm_SMD")
		(at 256.54 203.2 90)
		(unit 1)
		(exclude_from_sim no)
		(in_bom no)
		(on_board yes)
		(dnp no)
		(property "Reference" "TP8"
			(at 255.27 198.12 90)
			(effects
				(font
					(size 1.27 1.27)
					(thickness 0.15)
				)
				(justify right)
			)
		)
		(property "Value" "TP_1mm_SMD"
			(at 264.16 187.96 0)
			(effects
				(font
					(size 1.27 1.27)
					(thickness 0.15)
				)
				(justify left bottom)
				(hide yes)
			)
		)
		(property "Footprint" "antmicro-footprints:TP_SMD_1mm"
			(at 266.7 187.96 0)
			(effects
				(font
					(size 1.27 1.27)
					(thickness 0.15)
				)
				(justify left bottom)
				(hide yes)
			)
		)
		(property "Datasheet" ""
			(at 269.24 185.42 0)
			(effects
				(font
					(size 1.27 1.27)
					(thickness 0.15)
				)
				(justify left bottom)
				(hide yes)
			)
		)
		(property "Description" ""
			(at 256.54 203.2 0)
			(effects
				(font
					(size 1.27 1.27)
				)
				(hide yes)
			)
		)
		(property "License" "Apache-2.0"
			(at 274.32 187.96 0)
			(effects
				(font
					(size 1.27 1.27)
					(thickness 0.15)
				)
				(justify left bottom)
				(hide yes)
			)
		)
		(property "Manufacturer" ""
			(at 256.54 203.2 0)
			(effects
				(font
					(size 1.27 1.27)
				)
				(hide yes)
			)
		)
		(property "MPN" ""
			(at 256.54 203.2 0)
			(effects
				(font
					(size 1.27 1.27)
				)
				(hide yes)
			)
		)
		(property "Author" "Antmicro"
			(at 271.78 187.96 0)
			(effects
				(font
					(size 1.27 1.27)
					(thickness 0.15)
				)
				(justify left bottom)
				(hide yes)
			)
		)
		(pin "1"
		)
		(instances
			(project "thunderbolt-gpu-adapter"
				(path ""
					(reference "TP8")
					(unit 1)
				)
			)
		)
	)
	(symbol
		(lib_id "antmicropower:GND")
		(at 264.16 128.27 0)
		(unit 1)
		(exclude_from_sim no)
		(in_bom yes)
		(on_board yes)
		(dnp no)
		(property "Reference" "#PWR0201"
			(at 264.16 134.62 0)
			(effects
				(font
					(size 1.27 1.27)
				)
				(hide yes)
			)
		)
		(property "Value" "GND"
			(at 264.16 132.08 0)
			(effects
				(font
					(size 1.27 1.27)
				)
			)
		)
		(property "Footprint" ""
			(at 264.16 128.27 0)
			(effects
				(font
					(size 1.27 1.27)
				)
				(hide yes)
			)
		)
		(property "Datasheet" ""
			(at 264.16 128.27 0)
			(effects
				(font
					(size 1.27 1.27)
				)
				(hide yes)
			)
		)
		(property "Description" ""
			(at 264.16 128.27 0)
			(effects
				(font
					(size 1.27 1.27)
				)
				(hide yes)
			)
		)
		(property "Author" "Antmicro"
			(at 273.05 135.89 0)
			(effects
				(font
					(size 1.27 1.27)
					(thickness 0.15)
				)
				(justify left bottom)
				(hide yes)
			)
		)
		(property "License" "Apache-2.0"
			(at 273.05 138.43 0)
			(effects
				(font
					(size 1.27 1.27)
					(thickness 0.15)
				)
				(justify left bottom)
				(hide yes)
			)
		)
		(pin "1"
		)
		(instances
			(project "thunderbolt-gpu-adapter"
				(path ""
					(reference "#PWR0201")
					(unit 1)
				)
			)
		)
	)
	(symbol
		(lib_id "antmicroFerriteBeadsandChips:FB_30Z_8.5A_Murata-BLM21SN_0805")
		(at 209.55 346.71 0)
		(mirror x)
		(unit 1)
		(exclude_from_sim no)
		(in_bom yes)
		(on_board yes)
		(dnp no)
		(property "Reference" "FB3"
			(at 212.09 340.995 0)
			(effects
				(font
					(size 1.27 1.27)
					(thickness 0.15)
				)
			)
		)
		(property "Value" "FB_30Z_8.5A_Murata-BLM21SN_0805"
			(at 211.455 343.535 0)
			(effects
				(font
					(size 1.27 1.27)
					(thickness 0.15)
				)
				(hide yes)
			)
		)
		(property "Footprint" "antmicro-footprints:FB_0805_2012Metric"
			(at 223.52 341.63 0)
			(effects
				(font
					(size 1.27 1.27)
					(thickness 0.15)
				)
				(justify left bottom)
				(hide yes)
			)
		)
		(property "Datasheet" "https://www.murata.com/en-sg/products/productdata/8796738977822/ENFA0005.pdf?1519270210000"
			(at 223.52 339.09 0)
			(effects
				(font
					(size 1.27 1.27)
					(thickness 0.15)
				)
				(justify left bottom)
				(hide yes)
			)
		)
		(property "Description" ""
			(at 209.55 346.71 0)
			(effects
				(font
					(size 1.27 1.27)
				)
				(hide yes)
			)
		)
		(property "MPN" "BLM21SN300SZ1D"
			(at 223.52 336.55 0)
			(effects
				(font
					(size 1.27 1.27)
					(thickness 0.15)
				)
				(justify left bottom)
				(hide yes)
			)
		)
		(property "Manufacturer" "Murata"
			(at 223.52 334.01 0)
			(effects
				(font
					(size 1.27 1.27)
					(thickness 0.15)
				)
				(justify left bottom)
				(hide yes)
			)
		)
		(property "License" "Apache-2.0"
			(at 223.52 328.93 0)
			(effects
				(font
					(size 1.27 1.27)
					(thickness 0.15)
				)
				(justify left bottom)
				(hide yes)
			)
		)
		(property "Author" "Antmicro"
			(at 223.52 331.47 0)
			(effects
				(font
					(size 1.27 1.27)
					(thickness 0.15)
				)
				(justify left bottom)
				(hide yes)
			)
		)
		(property "Val" "30Z/8.5A"
			(at 207.01 342.9 0)
			(effects
				(font
					(size 1.27 1.27)
				)
				(justify left bottom)
			)
		)
		(property "Current" ""
			(at 229.87 323.85 0)
			(effects
				(font
					(size 1.27 1.27)
					(thickness 0.15)
				)
				(justify left bottom)
				(hide yes)
			)
		)
		(pin "1"
		)
		(pin "2"
		)
		(instances
			(project "thunderbolt-gpu-adapter"
				(path ""
					(reference "FB3")
					(unit 1)
				)
			)
		)
	)
	(symbol
		(lib_id "antmicropower:GND")
		(at 60.96 53.34 0)
		(unit 1)
		(exclude_from_sim no)
		(in_bom yes)
		(on_board yes)
		(dnp no)
		(property "Reference" "#PWR031"
			(at 60.96 59.69 0)
			(effects
				(font
					(size 1.27 1.27)
				)
				(hide yes)
			)
		)
		(property "Value" "GND"
			(at 60.96 57.15 0)
			(effects
				(font
					(size 1.27 1.27)
				)
			)
		)
		(property "Footprint" ""
			(at 60.96 53.34 0)
			(effects
				(font
					(size 1.27 1.27)
				)
				(hide yes)
			)
		)
		(property "Datasheet" ""
			(at 60.96 53.34 0)
			(effects
				(font
					(size 1.27 1.27)
				)
				(hide yes)
			)
		)
		(property "Description" ""
			(at 60.96 53.34 0)
			(effects
				(font
					(size 1.27 1.27)
				)
				(hide yes)
			)
		)
		(property "Author" "Antmicro"
			(at 69.85 60.96 0)
			(effects
				(font
					(size 1.27 1.27)
					(thickness 0.15)
				)
				(justify left bottom)
				(hide yes)
			)
		)
		(property "License" "Apache-2.0"
			(at 69.85 63.5 0)
			(effects
				(font
					(size 1.27 1.27)
					(thickness 0.15)
				)
				(justify left bottom)
				(hide yes)
			)
		)
		(pin "1"
		)
		(instances
			(project "thunderbolt-gpu-adapter"
				(path ""
					(reference "#PWR031")
					(unit 1)
				)
			)
		)
	)
	(symbol
		(lib_id "antmicroFixedInductors:L_6u8_12.8A_Coilcraft-XAL7070")
		(at 171.45 229.87 270)
		(unit 1)
		(exclude_from_sim no)
		(in_bom yes)
		(on_board yes)
		(dnp no)
		(fields_autoplaced yes)
		(property "Reference" "L1"
			(at 172.72 231.14 90)
			(effects
				(font
					(size 1.27 1.27)
					(thickness 0.15)
				)
				(justify left)
			)
		)
		(property "Value" "L_6u8_12.8A_Coilcraft-XAL7070"
			(at 168.91 243.84 0)
			(effects
				(font
					(size 1.27 1.27)
					(thickness 0.15)
				)
				(justify left bottom)
				(hide yes)
			)
		)
		(property "Footprint" "antmicro-footprints:L_Coilcraft-XAL7070"
			(at 163.83 243.84 0)
			(effects
				(font
					(size 1.27 1.27)
					(thickness 0.15)
				)
				(justify left bottom)
				(hide yes)
			)
		)
		(property "Datasheet" "https://www.coilcraft.com/en-us/products/power/shielded-inductors/molded-inductor/xal/xal7070/xal7070-682"
			(at 161.29 243.84 0)
			(effects
				(font
					(size 1.27 1.27)
					(thickness 0.15)
				)
				(justify left bottom)
				(hide yes)
			)
		)
		(property "Description" ""
			(at 171.45 229.87 0)
			(effects
				(font
					(size 1.27 1.27)
				)
				(hide yes)
			)
		)
		(property "Val" "6u8/12.8A"
			(at 172.72 233.68 90)
			(effects
				(font
					(size 1.27 1.27)
					(thickness 0.15)
				)
				(justify left)
			)
		)
		(property "Manufacturer" "Coilcraft"
			(at 158.75 243.84 0)
			(effects
				(font
					(size 1.27 1.27)
					(thickness 0.15)
				)
				(justify left bottom)
				(hide yes)
			)
		)
		(property "MPN" "XAL7070-682MEC"
			(at 156.21 243.84 0)
			(effects
				(font
					(size 1.27 1.27)
					(thickness 0.15)
				)
				(justify left bottom)
				(hide yes)
			)
		)
		(property "ISat" "12.8 A"
			(at 154.94 243.84 0)
			(effects
				(font
					(size 1.27 1.27)
				)
				(justify left)
				(hide yes)
			)
		)
		(property "IMax" "9.2 A"
			(at 151.13 243.84 0)
			(effects
				(font
					(size 1.27 1.27)
					(thickness 0.15)
				)
				(justify left bottom)
				(hide yes)
			)
		)
		(property "Size" "7.7x8"
			(at 148.59 243.84 0)
			(effects
				(font
					(size 1.27 1.27)
					(thickness 0.15)
				)
				(justify left bottom)
				(hide yes)
			)
		)
		(property "License" "Apache-2.0"
			(at 143.51 243.84 0)
			(effects
				(font
					(size 1.27 1.27)
					(thickness 0.15)
				)
				(justify left bottom)
				(hide yes)
			)
		)
		(property "Author" "Antmicro"
			(at 146.05 243.84 0)
			(effects
				(font
					(size 1.27 1.27)
					(thickness 0.15)
				)
				(justify left bottom)
				(hide yes)
			)
		)
		(pin "1"
		)
		(pin "2"
		)
		(instances
			(project "thunderbolt-gpu-adapter"
				(path ""
					(reference "L1")
					(unit 1)
				)
			)
		)
	)
	(symbol
		(lib_id "antmicropower:GND")
		(at 81.28 359.41 0)
		(unit 1)
		(exclude_from_sim no)
		(in_bom yes)
		(on_board yes)
		(dnp no)
		(property "Reference" "#PWR035"
			(at 81.28 365.76 0)
			(effects
				(font
					(size 1.27 1.27)
				)
				(hide yes)
			)
		)
		(property "Value" "GND"
			(at 81.28 363.22 0)
			(effects
				(font
					(size 1.27 1.27)
				)
			)
		)
		(property "Footprint" ""
			(at 81.28 359.41 0)
			(effects
				(font
					(size 1.27 1.27)
				)
				(hide yes)
			)
		)
		(property "Datasheet" ""
			(at 81.28 359.41 0)
			(effects
				(font
					(size 1.27 1.27)
				)
				(hide yes)
			)
		)
		(property "Description" ""
			(at 81.28 359.41 0)
			(effects
				(font
					(size 1.27 1.27)
				)
				(hide yes)
			)
		)
		(property "Author" "Antmicro"
			(at 90.17 367.03 0)
			(effects
				(font
					(size 1.27 1.27)
					(thickness 0.15)
				)
				(justify left bottom)
				(hide yes)
			)
		)
		(property "License" "Apache-2.0"
			(at 90.17 369.57 0)
			(effects
				(font
					(size 1.27 1.27)
					(thickness 0.15)
				)
				(justify left bottom)
				(hide yes)
			)
		)
		(pin "1"
		)
		(instances
			(project "thunderbolt-gpu-adapter"
				(path ""
					(reference "#PWR035")
					(unit 1)
				)
			)
		)
	)
	(symbol
		(lib_id "antmicroResistors0402:R_5k1_0402")
		(at 172.72 87.63 90)
		(unit 1)
		(exclude_from_sim no)
		(in_bom yes)
		(on_board yes)
		(dnp no)
		(fields_autoplaced yes)
		(property "Reference" "R40"
			(at 175.26 83.82 90)
			(effects
				(font
					(size 1.27 1.27)
					(thickness 0.15)
				)
				(justify right)
			)
		)
		(property "Value" "R_5k1_0402"
			(at 185.42 67.31 0)
			(effects
				(font
					(size 1.27 1.27)
					(thickness 0.15)
				)
				(justify left bottom)
				(hide yes)
			)
		)
		(property "Footprint" "antmicro-footprints:R_0402_1005Metric"
			(at 187.96 67.31 0)
			(effects
				(font
					(size 1.27 1.27)
					(thickness 0.15)
				)
				(justify left bottom)
				(hide yes)
			)
		)
		(property "Datasheet" "https://www.bourns.com/docs/product-datasheets/cr.pdf"
			(at 190.5 67.31 0)
			(effects
				(font
					(size 1.27 1.27)
					(thickness 0.15)
				)
				(justify left bottom)
				(hide yes)
			)
		)
		(property "Description" ""
			(at 172.72 87.63 0)
			(effects
				(font
					(size 1.27 1.27)
				)
				(hide yes)
			)
		)
		(property "MPN" "CR0402-FX-5101GLF"
			(at 193.04 67.31 0)
			(effects
				(font
					(size 1.27 1.27)
					(thickness 0.15)
				)
				(justify left bottom)
				(hide yes)
			)
		)
		(property "Manufacturer" "Bourns"
			(at 195.58 67.31 0)
			(effects
				(font
					(size 1.27 1.27)
					(thickness 0.15)
				)
				(justify left bottom)
				(hide yes)
			)
		)
		(property "License" "Apache-2.0"
			(at 198.12 67.31 0)
			(effects
				(font
					(size 1.27 1.27)
					(thickness 0.15)
				)
				(justify left bottom)
				(hide yes)
			)
		)
		(property "Val" "5k1"
			(at 175.26 86.36 90)
			(effects
				(font
					(size 1.27 1.27)
					(thickness 0.15)
				)
				(justify right)
			)
		)
		(property "Tolerance" "1%"
			(at 182.88 67.31 0)
			(effects
				(font
					(size 1.27 1.27)
				)
				(justify left bottom)
				(hide yes)
			)
		)
		(property "Author" "Antmicro"
			(at 200.66 67.31 0)
			(effects
				(font
					(size 1.27 1.27)
					(thickness 0.15)
				)
				(justify left bottom)
				(hide yes)
			)
		)
		(pin "1"
		)
		(pin "2"
		)
		(instances
			(project "thunderbolt-gpu-adapter"
				(path ""
					(reference "R40")
					(unit 1)
				)
			)
		)
	)
	(symbol
		(lib_id "antmicropower:GND")
		(at 167.64 257.81 0)
		(unit 1)
		(exclude_from_sim no)
		(in_bom yes)
		(on_board yes)
		(dnp no)
		(property "Reference" "#PWR0236"
			(at 167.64 264.16 0)
			(effects
				(font
					(size 1.27 1.27)
				)
				(hide yes)
			)
		)
		(property "Value" "GND"
			(at 165.735 262.255 0)
			(effects
				(font
					(size 1.27 1.27)
					(thickness 0.15)
				)
				(justify left bottom)
			)
		)
		(property "Footprint" ""
			(at 167.64 257.81 0)
			(effects
				(font
					(size 1.27 1.27)
					(thickness 0.15)
				)
				(justify left bottom)
				(hide yes)
			)
		)
		(property "Datasheet" ""
			(at 167.64 257.81 0)
			(effects
				(font
					(size 1.27 1.27)
					(thickness 0.15)
				)
				(justify left bottom)
				(hide yes)
			)
		)
		(property "Description" ""
			(at 167.64 257.81 0)
			(effects
				(font
					(size 1.27 1.27)
				)
				(hide yes)
			)
		)
		(property "Author" "Antmicro"
			(at 176.53 265.43 0)
			(effects
				(font
					(size 1.27 1.27)
					(thickness 0.15)
				)
				(justify left bottom)
				(hide yes)
			)
		)
		(property "License" "Apache-2.0"
			(at 176.53 267.97 0)
			(effects
				(font
					(size 1.27 1.27)
					(thickness 0.15)
				)
				(justify left bottom)
				(hide yes)
			)
		)
		(pin "1"
		)
		(instances
			(project "thunderbolt-gpu-adapter"
				(path ""
					(reference "#PWR0236")
					(unit 1)
				)
			)
		)
	)
	(symbol
		(lib_id "antmicroResistors0402:R_10k_0402")
		(at 74.93 356.87 90)
		(unit 1)
		(exclude_from_sim no)
		(in_bom yes)
		(on_board yes)
		(dnp no)
		(property "Reference" "R11"
			(at 76.2 353.06 90)
			(effects
				(font
					(size 1.27 1.27)
					(thickness 0.15)
				)
				(justify right)
			)
		)
		(property "Value" "R_10k_0402"
			(at 87.63 336.55 0)
			(effects
				(font
					(size 1.27 1.27)
					(thickness 0.15)
				)
				(justify left bottom)
				(hide yes)
			)
		)
		(property "Footprint" "antmicro-footprints:R_0402_1005Metric"
			(at 90.17 336.55 0)
			(effects
				(font
					(size 1.27 1.27)
					(thickness 0.15)
				)
				(justify left bottom)
				(hide yes)
			)
		)
		(property "Datasheet" "https://www.bourns.com/docs/product-datasheets/cr.pdf"
			(at 92.71 336.55 0)
			(effects
				(font
					(size 1.27 1.27)
					(thickness 0.15)
				)
				(justify left bottom)
				(hide yes)
			)
		)
		(property "Description" ""
			(at 74.93 356.87 0)
			(effects
				(font
					(size 1.27 1.27)
				)
				(hide yes)
			)
		)
		(property "MPN" "CR0402-FX-1002GLF"
			(at 95.25 336.55 0)
			(effects
				(font
					(size 1.27 1.27)
					(thickness 0.15)
				)
				(justify left bottom)
				(hide yes)
			)
		)
		(property "Manufacturer" "Bourns"
			(at 97.79 336.55 0)
			(effects
				(font
					(size 1.27 1.27)
					(thickness 0.15)
				)
				(justify left bottom)
				(hide yes)
			)
		)
		(property "License" "Apache-2.0"
			(at 100.33 336.55 0)
			(effects
				(font
					(size 1.27 1.27)
					(thickness 0.15)
				)
				(justify left bottom)
				(hide yes)
			)
		)
		(property "Val" "10k"
			(at 76.2 355.6 90)
			(effects
				(font
					(size 1.27 1.27)
					(thickness 0.15)
				)
				(justify right)
			)
		)
		(property "Tolerance" "1%"
			(at 85.09 336.55 0)
			(effects
				(font
					(size 1.27 1.27)
				)
				(justify left bottom)
				(hide yes)
			)
		)
		(property "Author" "Antmicro"
			(at 102.87 336.55 0)
			(effects
				(font
					(size 1.27 1.27)
					(thickness 0.15)
				)
				(justify left bottom)
				(hide yes)
			)
		)
		(pin "1"
		)
		(pin "2"
		)
		(instances
			(project "thunderbolt-gpu-adapter"
				(path ""
					(reference "R11")
					(unit 1)
				)
			)
		)
	)
	(symbol
		(lib_id "antmicropower:GND")
		(at 109.22 209.55 0)
		(unit 1)
		(exclude_from_sim no)
		(in_bom yes)
		(on_board yes)
		(dnp no)
		(property "Reference" "#PWR0231"
			(at 109.22 215.9 0)
			(effects
				(font
					(size 1.27 1.27)
				)
				(hide yes)
			)
		)
		(property "Value" "GND"
			(at 107.315 213.995 0)
			(effects
				(font
					(size 1.27 1.27)
					(thickness 0.15)
				)
				(justify left bottom)
			)
		)
		(property "Footprint" ""
			(at 109.22 209.55 0)
			(effects
				(font
					(size 1.27 1.27)
					(thickness 0.15)
				)
				(justify left bottom)
				(hide yes)
			)
		)
		(property "Datasheet" ""
			(at 109.22 209.55 0)
			(effects
				(font
					(size 1.27 1.27)
					(thickness 0.15)
				)
				(justify left bottom)
				(hide yes)
			)
		)
		(property "Description" ""
			(at 109.22 209.55 0)
			(effects
				(font
					(size 1.27 1.27)
				)
				(hide yes)
			)
		)
		(property "Author" "Antmicro"
			(at 118.11 217.17 0)
			(effects
				(font
					(size 1.27 1.27)
					(thickness 0.15)
				)
				(justify left bottom)
				(hide yes)
			)
		)
		(property "License" "Apache-2.0"
			(at 118.11 219.71 0)
			(effects
				(font
					(size 1.27 1.27)
					(thickness 0.15)
				)
				(justify left bottom)
				(hide yes)
			)
		)
		(pin "1"
		)
		(instances
			(project "thunderbolt-gpu-adapter"
				(path ""
					(reference "#PWR0231")
					(unit 1)
				)
			)
		)
	)
	(symbol
		(lib_id "antmicropower:GND")
		(at 74.93 340.36 0)
		(unit 1)
		(exclude_from_sim no)
		(in_bom yes)
		(on_board yes)
		(dnp no)
		(property "Reference" "#PWR023"
			(at 74.93 346.71 0)
			(effects
				(font
					(size 1.27 1.27)
				)
				(hide yes)
			)
		)
		(property "Value" "GND"
			(at 74.93 344.17 0)
			(effects
				(font
					(size 1.27 1.27)
				)
			)
		)
		(property "Footprint" ""
			(at 74.93 340.36 0)
			(effects
				(font
					(size 1.27 1.27)
				)
				(hide yes)
			)
		)
		(property "Datasheet" ""
			(at 74.93 340.36 0)
			(effects
				(font
					(size 1.27 1.27)
				)
				(hide yes)
			)
		)
		(property "Description" ""
			(at 74.93 340.36 0)
			(effects
				(font
					(size 1.27 1.27)
				)
				(hide yes)
			)
		)
		(property "Author" "Antmicro"
			(at 83.82 347.98 0)
			(effects
				(font
					(size 1.27 1.27)
					(thickness 0.15)
				)
				(justify left bottom)
				(hide yes)
			)
		)
		(property "License" "Apache-2.0"
			(at 83.82 350.52 0)
			(effects
				(font
					(size 1.27 1.27)
					(thickness 0.15)
				)
				(justify left bottom)
				(hide yes)
			)
		)
		(pin "1"
		)
		(instances
			(project "thunderbolt-gpu-adapter"
				(path ""
					(reference "#PWR023")
					(unit 1)
				)
			)
		)
	)
	(symbol
		(lib_id "antmicropower:GND")
		(at 74.93 359.41 0)
		(unit 1)
		(exclude_from_sim no)
		(in_bom yes)
		(on_board yes)
		(dnp no)
		(property "Reference" "#PWR026"
			(at 74.93 365.76 0)
			(effects
				(font
					(size 1.27 1.27)
				)
				(hide yes)
			)
		)
		(property "Value" "GND"
			(at 74.93 363.22 0)
			(effects
				(font
					(size 1.27 1.27)
				)
			)
		)
		(property "Footprint" ""
			(at 74.93 359.41 0)
			(effects
				(font
					(size 1.27 1.27)
				)
				(hide yes)
			)
		)
		(property "Datasheet" ""
			(at 74.93 359.41 0)
			(effects
				(font
					(size 1.27 1.27)
				)
				(hide yes)
			)
		)
		(property "Description" ""
			(at 74.93 359.41 0)
			(effects
				(font
					(size 1.27 1.27)
				)
				(hide yes)
			)
		)
		(property "Author" "Antmicro"
			(at 83.82 367.03 0)
			(effects
				(font
					(size 1.27 1.27)
					(thickness 0.15)
				)
				(justify left bottom)
				(hide yes)
			)
		)
		(property "License" "Apache-2.0"
			(at 83.82 369.57 0)
			(effects
				(font
					(size 1.27 1.27)
					(thickness 0.15)
				)
				(justify left bottom)
				(hide yes)
			)
		)
		(pin "1"
		)
		(instances
			(project "thunderbolt-gpu-adapter"
				(path ""
					(reference "#PWR026")
					(unit 1)
				)
			)
		)
	)
	(symbol
		(lib_id "antmicropower:GND")
		(at 92.71 340.36 0)
		(unit 1)
		(exclude_from_sim no)
		(in_bom yes)
		(on_board yes)
		(dnp no)
		(property "Reference" "#PWR036"
			(at 92.71 346.71 0)
			(effects
				(font
					(size 1.27 1.27)
				)
				(hide yes)
			)
		)
		(property "Value" "GND"
			(at 92.71 344.17 0)
			(effects
				(font
					(size 1.27 1.27)
				)
			)
		)
		(property "Footprint" ""
			(at 92.71 340.36 0)
			(effects
				(font
					(size 1.27 1.27)
				)
				(hide yes)
			)
		)
		(property "Datasheet" ""
			(at 92.71 340.36 0)
			(effects
				(font
					(size 1.27 1.27)
				)
				(hide yes)
			)
		)
		(property "Description" ""
			(at 92.71 340.36 0)
			(effects
				(font
					(size 1.27 1.27)
				)
				(hide yes)
			)
		)
		(property "Author" "Antmicro"
			(at 101.6 347.98 0)
			(effects
				(font
					(size 1.27 1.27)
					(thickness 0.15)
				)
				(justify left bottom)
				(hide yes)
			)
		)
		(property "License" "Apache-2.0"
			(at 101.6 350.52 0)
			(effects
				(font
					(size 1.27 1.27)
					(thickness 0.15)
				)
				(justify left bottom)
				(hide yes)
			)
		)
		(pin "1"
		)
		(instances
			(project "thunderbolt-gpu-adapter"
				(path ""
					(reference "#PWR036")
					(unit 1)
				)
			)
		)
	)
	(symbol
		(lib_id "antmicroResistors0603:R_0R_22.4A_0603")
		(at 261.62 300.99 180)
		(unit 1)
		(exclude_from_sim no)
		(in_bom yes)
		(on_board yes)
		(dnp no)
		(property "Reference" "R99"
			(at 259.08 299.085 0)
			(effects
				(font
					(size 1.27 1.27)
					(thickness 0.15)
				)
			)
		)
		(property "Value" "R_0R_22.4A_0603"
			(at 271.78 293.37 0)
			(effects
				(font
					(size 1.27 1.27)
					(thickness 0.15)
				)
				(hide yes)
			)
		)
		(property "Footprint" "antmicro-footprints:R_0603_1608Metric"
			(at 238.76 288.29 0)
			(effects
				(font
					(size 1.27 1.27)
					(thickness 0.15)
				)
				(justify left bottom)
				(hide yes)
			)
		)
		(property "Datasheet" "https://fscdn.rohm.com/en/products/databook/datasheet/passive/resistor/chip_resistor/pmr-jpw-e.pdf"
			(at 238.76 285.75 0)
			(effects
				(font
					(size 1.27 1.27)
					(thickness 0.15)
				)
				(justify left bottom)
				(hide yes)
			)
		)
		(property "Description" ""
			(at 261.62 300.99 0)
			(effects
				(font
					(size 1.27 1.27)
				)
				(hide yes)
			)
		)
		(property "Manufacturer" "ROHM Semiconductor"
			(at 238.76 283.21 0)
			(effects
				(font
					(size 1.27 1.27)
					(thickness 0.15)
				)
				(justify left bottom)
				(hide yes)
			)
		)
		(property "MPN" "PMR03EZPJ000"
			(at 238.76 280.67 0)
			(effects
				(font
					(size 1.27 1.27)
					(thickness 0.15)
				)
				(justify left bottom)
				(hide yes)
			)
		)
		(property "Val" "0R"
			(at 259.08 300.99 0)
			(effects
				(font
					(size 1.27 1.27)
					(thickness 0.15)
				)
			)
		)
		(property "Author" "Antmicro"
			(at 238.76 278.13 0)
			(effects
				(font
					(size 1.27 1.27)
					(thickness 0.15)
				)
				(justify left bottom)
				(hide yes)
			)
		)
		(property "License" "Apache-2.0"
			(at 238.76 275.59 0)
			(effects
				(font
					(size 1.27 1.27)
					(thickness 0.15)
				)
				(justify left bottom)
				(hide yes)
			)
		)
		(property "Max. Curr." "22.4A"
			(at 259.08 297.18 0)
			(effects
				(font
					(size 1.27 1.27)
					(thickness 0.15)
				)
			)
		)
		(property "Tolerance" "template_tolerance"
			(at 241.3 290.83 0)
			(effects
				(font
					(size 1.27 1.27)
				)
				(justify left bottom)
				(hide yes)
			)
		)
		(pin "1"
		)
		(pin "2"
		)
		(instances
			(project "thunderbolt-gpu-adapter"
				(path ""
					(reference "R99")
					(unit 1)
				)
			)
		)
	)
	(symbol
		(lib_id "antmicropower:GND")
		(at 96.52 213.36 0)
		(unit 1)
		(exclude_from_sim no)
		(in_bom yes)
		(on_board yes)
		(dnp no)
		(property "Reference" "#PWR0230"
			(at 96.52 219.71 0)
			(effects
				(font
					(size 1.27 1.27)
				)
				(hide yes)
			)
		)
		(property "Value" "GND"
			(at 94.615 217.805 0)
			(effects
				(font
					(size 1.27 1.27)
					(thickness 0.15)
				)
				(justify left bottom)
			)
		)
		(property "Footprint" ""
			(at 96.52 213.36 0)
			(effects
				(font
					(size 1.27 1.27)
					(thickness 0.15)
				)
				(justify left bottom)
				(hide yes)
			)
		)
		(property "Datasheet" ""
			(at 96.52 213.36 0)
			(effects
				(font
					(size 1.27 1.27)
					(thickness 0.15)
				)
				(justify left bottom)
				(hide yes)
			)
		)
		(property "Description" ""
			(at 96.52 213.36 0)
			(effects
				(font
					(size 1.27 1.27)
				)
				(hide yes)
			)
		)
		(property "Author" "Antmicro"
			(at 105.41 220.98 0)
			(effects
				(font
					(size 1.27 1.27)
					(thickness 0.15)
				)
				(justify left bottom)
				(hide yes)
			)
		)
		(property "License" "Apache-2.0"
			(at 105.41 223.52 0)
			(effects
				(font
					(size 1.27 1.27)
					(thickness 0.15)
				)
				(justify left bottom)
				(hide yes)
			)
		)
		(pin "1"
		)
		(instances
			(project "thunderbolt-gpu-adapter"
				(path ""
					(reference "#PWR0230")
					(unit 1)
				)
			)
		)
	)
	(symbol
		(lib_id "antmicroResistors0402:R_0R_0402")
		(at 123.19 243.84 270)
		(unit 1)
		(exclude_from_sim no)
		(in_bom yes)
		(on_board yes)
		(dnp no)
		(property "Reference" "R27"
			(at 120.65 245.11 90)
			(effects
				(font
					(size 1.27 1.27)
					(thickness 0.15)
				)
				(justify right)
			)
		)
		(property "Value" "R_0R_0402"
			(at 110.49 264.16 0)
			(effects
				(font
					(size 1.27 1.27)
					(thickness 0.15)
				)
				(justify left bottom)
				(hide yes)
			)
		)
		(property "Footprint" "antmicro-footprints:R_0402_1005Metric"
			(at 107.95 264.16 0)
			(effects
				(font
					(size 1.27 1.27)
					(thickness 0.15)
				)
				(justify left bottom)
				(hide yes)
			)
		)
		(property "Datasheet" "https://industrial.panasonic.com/cdbs/www-data/pdf/RDA0000/AOA0000C301.pdf"
			(at 105.41 264.16 0)
			(effects
				(font
					(size 1.27 1.27)
					(thickness 0.15)
				)
				(justify left bottom)
				(hide yes)
			)
		)
		(property "Description" ""
			(at 123.19 243.84 0)
			(effects
				(font
					(size 1.27 1.27)
				)
				(hide yes)
			)
		)
		(property "MPN" "ERJ2GE0R00X"
			(at 102.87 264.16 0)
			(effects
				(font
					(size 1.27 1.27)
					(thickness 0.15)
				)
				(justify left bottom)
				(hide yes)
			)
		)
		(property "Manufacturer" "Panasonic"
			(at 100.33 264.16 0)
			(effects
				(font
					(size 1.27 1.27)
					(thickness 0.15)
				)
				(justify left bottom)
				(hide yes)
			)
		)
		(property "License" "Apache-2.0"
			(at 97.79 264.16 0)
			(effects
				(font
					(size 1.27 1.27)
					(thickness 0.15)
				)
				(justify left bottom)
				(hide yes)
			)
		)
		(property "Val" "0R"
			(at 120.65 247.65 90)
			(effects
				(font
					(size 1.27 1.27)
					(thickness 0.15)
				)
				(justify right)
			)
		)
		(property "Tolerance" "~"
			(at 113.03 264.16 0)
			(effects
				(font
					(size 1.27 1.27)
				)
				(justify left bottom)
				(hide yes)
			)
		)
		(property "Current" "1A"
			(at 92.71 264.16 0)
			(effects
				(font
					(size 1.27 1.27)
					(thickness 0.15)
				)
				(justify left bottom)
				(hide yes)
			)
		)
		(property "Author" "Antmicro"
			(at 95.25 264.16 0)
			(effects
				(font
					(size 1.27 1.27)
					(thickness 0.15)
				)
				(justify left bottom)
				(hide yes)
			)
		)
		(pin "1"
		)
		(pin "2"
		)
		(instances
			(project "thunderbolt-gpu-adapter"
				(path ""
					(reference "R27")
					(unit 1)
				)
			)
		)
	)
	(symbol
		(lib_id "antmicroResistors0402:R_0R_0402")
		(at 64.77 102.87 0)
		(unit 1)
		(exclude_from_sim no)
		(in_bom yes)
		(on_board yes)
		(dnp no)
		(fields_autoplaced yes)
		(property "Reference" "R18"
			(at 67.31 100.965 0)
			(effects
				(font
					(size 1.27 1.27)
					(thickness 0.15)
				)
			)
		)
		(property "Value" "R_0R_0402"
			(at 85.09 115.57 0)
			(effects
				(font
					(size 1.27 1.27)
					(thickness 0.15)
				)
				(justify left bottom)
				(hide yes)
			)
		)
		(property "Footprint" "antmicro-footprints:R_0402_1005Metric"
			(at 85.09 118.11 0)
			(effects
				(font
					(size 1.27 1.27)
					(thickness 0.15)
				)
				(justify left bottom)
				(hide yes)
			)
		)
		(property "Datasheet" "https://industrial.panasonic.com/cdbs/www-data/pdf/RDA0000/AOA0000C301.pdf"
			(at 85.09 120.65 0)
			(effects
				(font
					(size 1.27 1.27)
					(thickness 0.15)
				)
				(justify left bottom)
				(hide yes)
			)
		)
		(property "Description" ""
			(at 64.77 102.87 0)
			(effects
				(font
					(size 1.27 1.27)
				)
				(hide yes)
			)
		)
		(property "MPN" "ERJ2GE0R00X"
			(at 85.09 123.19 0)
			(effects
				(font
					(size 1.27 1.27)
					(thickness 0.15)
				)
				(justify left bottom)
				(hide yes)
			)
		)
		(property "Manufacturer" "Panasonic"
			(at 85.09 125.73 0)
			(effects
				(font
					(size 1.27 1.27)
					(thickness 0.15)
				)
				(justify left bottom)
				(hide yes)
			)
		)
		(property "License" "Apache-2.0"
			(at 85.09 128.27 0)
			(effects
				(font
					(size 1.27 1.27)
					(thickness 0.15)
				)
				(justify left bottom)
				(hide yes)
			)
		)
		(property "Val" "0R"
			(at 67.31 102.87 0)
			(effects
				(font
					(size 1.27 1.27)
					(thickness 0.15)
				)
			)
		)
		(property "Tolerance" "~"
			(at 85.09 113.03 0)
			(effects
				(font
					(size 1.27 1.27)
				)
				(justify left bottom)
				(hide yes)
			)
		)
		(property "Current" "1A"
			(at 67.31 99.06 0)
			(effects
				(font
					(size 1.27 1.27)
					(thickness 0.15)
				)
				(hide yes)
			)
		)
		(property "Author" "Antmicro"
			(at 85.09 130.81 0)
			(effects
				(font
					(size 1.27 1.27)
					(thickness 0.15)
				)
				(justify left bottom)
				(hide yes)
			)
		)
		(pin "1"
		)
		(pin "2"
		)
		(instances
			(project "thunderbolt-gpu-adapter"
				(path ""
					(reference "R18")
					(unit 1)
				)
			)
		)
	)
	(symbol
		(lib_id "antmicroCapacitors0603:C_22u_16V_0603")
		(at 262.89 213.36 90)
		(unit 1)
		(exclude_from_sim no)
		(in_bom yes)
		(on_board yes)
		(dnp no)
		(property "Reference" "C50"
			(at 265.43 209.5436 90)
			(effects
				(font
					(size 1.27 1.27)
					(thickness 0.15)
				)
				(justify right)
			)
		)
		(property "Value" "C_22u_16V_0603"
			(at 273.05 193.04 0)
			(effects
				(font
					(size 1.27 1.27)
					(thickness 0.15)
				)
				(justify left bottom)
				(hide yes)
			)
		)
		(property "Footprint" "antmicro-footprints:C_0603_1608Metric"
			(at 275.59 193.04 0)
			(effects
				(font
					(size 1.27 1.27)
					(thickness 0.15)
				)
				(justify left bottom)
				(hide yes)
			)
		)
		(property "Datasheet" "https://product.samsungsem.com/mlcc/CL10A226MO7JZN.do"
			(at 278.13 193.04 0)
			(effects
				(font
					(size 1.27 1.27)
					(thickness 0.15)
				)
				(justify left bottom)
				(hide yes)
			)
		)
		(property "Description" ""
			(at 262.89 213.36 0)
			(effects
				(font
					(size 1.27 1.27)
				)
				(hide yes)
			)
		)
		(property "MPN" "CL10A226MO7JZNC"
			(at 280.67 193.04 0)
			(effects
				(font
					(size 1.27 1.27)
					(thickness 0.15)
				)
				(justify left bottom)
				(hide yes)
			)
		)
		(property "Manufacturer" "Samsung Electro-Mechanics"
			(at 283.21 193.04 0)
			(effects
				(font
					(size 1.27 1.27)
					(thickness 0.15)
				)
				(justify left bottom)
				(hide yes)
			)
		)
		(property "License" "Apache-2.0"
			(at 285.75 193.04 0)
			(effects
				(font
					(size 1.27 1.27)
					(thickness 0.15)
				)
				(justify left bottom)
				(hide yes)
			)
		)
		(property "Val" "22u"
			(at 265.43 212.0836 90)
			(effects
				(font
					(size 1.27 1.27)
					(thickness 0.15)
				)
				(justify right)
			)
		)
		(property "Voltage" "16V"
			(at 290.83 193.04 0)
			(effects
				(font
					(size 1.27 1.27)
				)
				(justify left bottom)
				(hide yes)
			)
		)
		(property "Dielectric" ""
			(at 293.37 193.04 0)
			(effects
				(font
					(size 1.27 1.27)
				)
				(justify left bottom)
				(hide yes)
			)
		)
		(property "Author" "Antmicro"
			(at 288.29 193.04 0)
			(effects
				(font
					(size 1.27 1.27)
					(thickness 0.15)
				)
				(justify left bottom)
				(hide yes)
			)
		)
		(pin "1"
		)
		(pin "2"
		)
		(instances
			(project "thunderbolt-gpu-adapter"
				(path ""
					(reference "C50")
					(unit 1)
				)
			)
		)
	)
	(symbol
		(lib_id "antmicropower:GND")
		(at 86.36 207.01 0)
		(unit 1)
		(exclude_from_sim no)
		(in_bom yes)
		(on_board yes)
		(dnp no)
		(property "Reference" "#PWR0229"
			(at 86.36 213.36 0)
			(effects
				(font
					(size 1.27 1.27)
				)
				(hide yes)
			)
		)
		(property "Value" "GND"
			(at 84.455 211.455 0)
			(effects
				(font
					(size 1.27 1.27)
					(thickness 0.15)
				)
				(justify left bottom)
			)
		)
		(property "Footprint" ""
			(at 86.36 207.01 0)
			(effects
				(font
					(size 1.27 1.27)
					(thickness 0.15)
				)
				(justify left bottom)
				(hide yes)
			)
		)
		(property "Datasheet" ""
			(at 86.36 207.01 0)
			(effects
				(font
					(size 1.27 1.27)
					(thickness 0.15)
				)
				(justify left bottom)
				(hide yes)
			)
		)
		(property "Description" ""
			(at 86.36 207.01 0)
			(effects
				(font
					(size 1.27 1.27)
				)
				(hide yes)
			)
		)
		(property "Author" "Antmicro"
			(at 95.25 214.63 0)
			(effects
				(font
					(size 1.27 1.27)
					(thickness 0.15)
				)
				(justify left bottom)
				(hide yes)
			)
		)
		(property "License" "Apache-2.0"
			(at 95.25 217.17 0)
			(effects
				(font
					(size 1.27 1.27)
					(thickness 0.15)
				)
				(justify left bottom)
				(hide yes)
			)
		)
		(pin "1"
		)
		(instances
			(project "thunderbolt-gpu-adapter"
				(path ""
					(reference "#PWR0229")
					(unit 1)
				)
			)
		)
	)
	(symbol
		(lib_id "antmicroResistors0402:R_5k1_0402")
		(at 154.94 87.63 270)
		(mirror x)
		(unit 1)
		(exclude_from_sim no)
		(in_bom yes)
		(on_board yes)
		(dnp no)
		(property "Reference" "R38"
			(at 152.4 83.82 90)
			(effects
				(font
					(size 1.27 1.27)
					(thickness 0.15)
				)
				(justify right)
			)
		)
		(property "Value" "R_5k1_0402"
			(at 142.24 67.31 0)
			(effects
				(font
					(size 1.27 1.27)
					(thickness 0.15)
				)
				(justify left bottom)
				(hide yes)
			)
		)
		(property "Footprint" "antmicro-footprints:R_0402_1005Metric"
			(at 139.7 67.31 0)
			(effects
				(font
					(size 1.27 1.27)
					(thickness 0.15)
				)
				(justify left bottom)
				(hide yes)
			)
		)
		(property "Datasheet" "https://www.bourns.com/docs/product-datasheets/cr.pdf"
			(at 137.16 67.31 0)
			(effects
				(font
					(size 1.27 1.27)
					(thickness 0.15)
				)
				(justify left bottom)
				(hide yes)
			)
		)
		(property "Description" ""
			(at 154.94 87.63 0)
			(effects
				(font
					(size 1.27 1.27)
				)
				(hide yes)
			)
		)
		(property "MPN" "CR0402-FX-5101GLF"
			(at 134.62 67.31 0)
			(effects
				(font
					(size 1.27 1.27)
					(thickness 0.15)
				)
				(justify left bottom)
				(hide yes)
			)
		)
		(property "Manufacturer" "Bourns"
			(at 132.08 67.31 0)
			(effects
				(font
					(size 1.27 1.27)
					(thickness 0.15)
				)
				(justify left bottom)
				(hide yes)
			)
		)
		(property "License" "Apache-2.0"
			(at 129.54 67.31 0)
			(effects
				(font
					(size 1.27 1.27)
					(thickness 0.15)
				)
				(justify left bottom)
				(hide yes)
			)
		)
		(property "Val" "5k1"
			(at 152.4 86.36 90)
			(effects
				(font
					(size 1.27 1.27)
					(thickness 0.15)
				)
				(justify right)
			)
		)
		(property "Tolerance" "1%"
			(at 144.78 67.31 0)
			(effects
				(font
					(size 1.27 1.27)
				)
				(justify left bottom)
				(hide yes)
			)
		)
		(property "Author" "Antmicro"
			(at 127 67.31 0)
			(effects
				(font
					(size 1.27 1.27)
					(thickness 0.15)
				)
				(justify left bottom)
				(hide yes)
			)
		)
		(pin "1"
		)
		(pin "2"
		)
		(instances
			(project "thunderbolt-gpu-adapter"
				(path ""
					(reference "R38")
					(unit 1)
				)
			)
		)
	)
	(symbol
		(lib_id "antmicroResistors0402:R_10k_0402")
		(at 64.77 92.71 0)
		(unit 1)
		(exclude_from_sim no)
		(in_bom yes)
		(on_board yes)
		(dnp no)
		(fields_autoplaced yes)
		(property "Reference" "R17"
			(at 67.31 90.805 0)
			(effects
				(font
					(size 1.27 1.27)
					(thickness 0.15)
				)
			)
		)
		(property "Value" "R_10k_0402"
			(at 85.09 105.41 0)
			(effects
				(font
					(size 1.27 1.27)
					(thickness 0.15)
				)
				(justify left bottom)
				(hide yes)
			)
		)
		(property "Footprint" "antmicro-footprints:R_0402_1005Metric"
			(at 85.09 107.95 0)
			(effects
				(font
					(size 1.27 1.27)
					(thickness 0.15)
				)
				(justify left bottom)
				(hide yes)
			)
		)
		(property "Datasheet" "https://www.bourns.com/docs/product-datasheets/cr.pdf"
			(at 85.09 110.49 0)
			(effects
				(font
					(size 1.27 1.27)
					(thickness 0.15)
				)
				(justify left bottom)
				(hide yes)
			)
		)
		(property "Description" ""
			(at 64.77 92.71 0)
			(effects
				(font
					(size 1.27 1.27)
				)
				(hide yes)
			)
		)
		(property "MPN" "CR0402-FX-1002GLF"
			(at 85.09 113.03 0)
			(effects
				(font
					(size 1.27 1.27)
					(thickness 0.15)
				)
				(justify left bottom)
				(hide yes)
			)
		)
		(property "Manufacturer" "Bourns"
			(at 85.09 115.57 0)
			(effects
				(font
					(size 1.27 1.27)
					(thickness 0.15)
				)
				(justify left bottom)
				(hide yes)
			)
		)
		(property "License" "Apache-2.0"
			(at 85.09 118.11 0)
			(effects
				(font
					(size 1.27 1.27)
					(thickness 0.15)
				)
				(justify left bottom)
				(hide yes)
			)
		)
		(property "Val" "10k"
			(at 67.31 94.615 0)
			(effects
				(font
					(size 1.27 1.27)
					(thickness 0.15)
				)
			)
		)
		(property "Tolerance" "1%"
			(at 85.09 102.87 0)
			(effects
				(font
					(size 1.27 1.27)
				)
				(justify left bottom)
				(hide yes)
			)
		)
		(property "Author" "Antmicro"
			(at 85.09 120.65 0)
			(effects
				(font
					(size 1.27 1.27)
					(thickness 0.15)
				)
				(justify left bottom)
				(hide yes)
			)
		)
		(pin "1"
		)
		(pin "2"
		)
		(instances
			(project "thunderbolt-gpu-adapter"
				(path ""
					(reference "R17")
					(unit 1)
				)
			)
		)
	)
	(symbol
		(lib_id "antmicroResistors0402:R_10k_0402")
		(at 71.12 349.25 180)
		(unit 1)
		(exclude_from_sim no)
		(in_bom yes)
		(on_board yes)
		(dnp no)
		(fields_autoplaced yes)
		(property "Reference" "R6"
			(at 68.58 353.06 0)
			(effects
				(font
					(size 1.27 1.27)
					(thickness 0.15)
				)
			)
		)
		(property "Value" "R_10k_0402"
			(at 50.8 336.55 0)
			(effects
				(font
					(size 1.27 1.27)
					(thickness 0.15)
				)
				(justify left bottom)
				(hide yes)
			)
		)
		(property "Footprint" "antmicro-footprints:R_0402_1005Metric"
			(at 50.8 334.01 0)
			(effects
				(font
					(size 1.27 1.27)
					(thickness 0.15)
				)
				(justify left bottom)
				(hide yes)
			)
		)
		(property "Datasheet" "https://www.bourns.com/docs/product-datasheets/cr.pdf"
			(at 50.8 331.47 0)
			(effects
				(font
					(size 1.27 1.27)
					(thickness 0.15)
				)
				(justify left bottom)
				(hide yes)
			)
		)
		(property "Description" ""
			(at 71.12 349.25 0)
			(effects
				(font
					(size 1.27 1.27)
				)
				(hide yes)
			)
		)
		(property "MPN" "CR0402-FX-1002GLF"
			(at 50.8 328.93 0)
			(effects
				(font
					(size 1.27 1.27)
					(thickness 0.15)
				)
				(justify left bottom)
				(hide yes)
			)
		)
		(property "Manufacturer" "Bourns"
			(at 50.8 326.39 0)
			(effects
				(font
					(size 1.27 1.27)
					(thickness 0.15)
				)
				(justify left bottom)
				(hide yes)
			)
		)
		(property "License" "Apache-2.0"
			(at 50.8 323.85 0)
			(effects
				(font
					(size 1.27 1.27)
					(thickness 0.15)
				)
				(justify left bottom)
				(hide yes)
			)
		)
		(property "Val" "10k"
			(at 68.58 355.6 0)
			(effects
				(font
					(size 1.27 1.27)
					(thickness 0.15)
				)
			)
		)
		(property "Tolerance" "1%"
			(at 50.8 339.09 0)
			(effects
				(font
					(size 1.27 1.27)
				)
				(justify left bottom)
				(hide yes)
			)
		)
		(property "Author" "Antmicro"
			(at 50.8 321.31 0)
			(effects
				(font
					(size 1.27 1.27)
					(thickness 0.15)
				)
				(justify left bottom)
				(hide yes)
			)
		)
		(pin "1"
		)
		(pin "2"
		)
		(instances
			(project "thunderbolt-gpu-adapter"
				(path ""
					(reference "R6")
					(unit 1)
				)
			)
		)
	)
	(symbol
		(lib_id "antmicroCapacitorspol:C_Pol_330u_6.3V_KEMET-T520-B")
		(at 25.4 34.29 270)
		(unit 1)
		(exclude_from_sim no)
		(in_bom yes)
		(on_board yes)
		(dnp yes)
		(fields_autoplaced yes)
		(property "Reference" "C153"
			(at 27.94 35.0266 90)
			(effects
				(font
					(size 1.27 1.27)
					(thickness 0.15)
				)
				(justify left)
			)
		)
		(property "Value" "C_Pol_330u_6.3V_KEMET-T520-B"
			(at 22.86 48.26 0)
			(effects
				(font
					(size 1.27 1.27)
					(thickness 0.15)
				)
				(justify left bottom)
				(hide yes)
			)
		)
		(property "Footprint" "antmicro-footprints:C_Pol_EIA-B"
			(at 17.78 48.26 0)
			(effects
				(font
					(size 1.27 1.27)
					(thickness 0.15)
				)
				(justify left bottom)
				(hide yes)
			)
		)
		(property "Datasheet" "https://www.kemet.com/en/us/capacitors/product/T520B337M006ATE040.html"
			(at 15.24 48.26 0)
			(effects
				(font
					(size 1.27 1.27)
					(thickness 0.15)
				)
				(justify left bottom)
				(hide yes)
			)
		)
		(property "Description" ""
			(at 25.4 34.29 0)
			(effects
				(font
					(size 1.27 1.27)
				)
				(hide yes)
			)
		)
		(property "Val" "330u"
			(at 27.94 37.5666 90)
			(effects
				(font
					(size 1.27 1.27)
					(thickness 0.15)
				)
				(justify left)
			)
		)
		(property "MPN" "T520B337M006ATE040"
			(at 12.7 48.26 0)
			(effects
				(font
					(size 1.27 1.27)
					(thickness 0.15)
				)
				(justify left bottom)
				(hide yes)
			)
		)
		(property "Manufacturer" "KEMET"
			(at 10.16 48.26 0)
			(effects
				(font
					(size 1.27 1.27)
					(thickness 0.15)
				)
				(justify left bottom)
				(hide yes)
			)
		)
		(property "License" "Apache-2.0"
			(at 7.62 48.26 0)
			(effects
				(font
					(size 1.27 1.27)
					(thickness 0.15)
				)
				(justify left bottom)
				(hide yes)
			)
		)
		(property "Author" "Antmicro"
			(at 5.08 48.26 0)
			(effects
				(font
					(size 1.27 1.27)
					(thickness 0.15)
				)
				(justify left bottom)
				(hide yes)
			)
		)
		(property "Voltage" "6.3V"
			(at 2.54 48.26 0)
			(effects
				(font
					(size 1.27 1.27)
				)
				(justify left bottom)
				(hide yes)
			)
		)
		(property "Dielectric" "template_dielectric"
			(at 0 48.26 0)
			(effects
				(font
					(size 1.27 1.27)
				)
				(justify left bottom)
				(hide yes)
			)
		)
		(pin "1"
		)
		(pin "2"
		)
		(instances
			(project "thunderbolt-gpu-adapter"
				(path ""
					(reference "C153")
					(unit 1)
				)
			)
		)
	)
	(symbol
		(lib_id "antmicropower:GND")
		(at 93.98 363.22 0)
		(unit 1)
		(exclude_from_sim no)
		(in_bom yes)
		(on_board yes)
		(dnp no)
		(property "Reference" "#PWR037"
			(at 93.98 369.57 0)
			(effects
				(font
					(size 1.27 1.27)
				)
				(hide yes)
			)
		)
		(property "Value" "GND"
			(at 93.98 367.03 0)
			(effects
				(font
					(size 1.27 1.27)
				)
			)
		)
		(property "Footprint" ""
			(at 93.98 363.22 0)
			(effects
				(font
					(size 1.27 1.27)
				)
				(hide yes)
			)
		)
		(property "Datasheet" ""
			(at 93.98 363.22 0)
			(effects
				(font
					(size 1.27 1.27)
				)
				(hide yes)
			)
		)
		(property "Description" ""
			(at 93.98 363.22 0)
			(effects
				(font
					(size 1.27 1.27)
				)
				(hide yes)
			)
		)
		(property "Author" "Antmicro"
			(at 102.87 370.84 0)
			(effects
				(font
					(size 1.27 1.27)
					(thickness 0.15)
				)
				(justify left bottom)
				(hide yes)
			)
		)
		(property "License" "Apache-2.0"
			(at 102.87 373.38 0)
			(effects
				(font
					(size 1.27 1.27)
					(thickness 0.15)
				)
				(justify left bottom)
				(hide yes)
			)
		)
		(pin "1"
		)
		(instances
			(project "thunderbolt-gpu-adapter"
				(path ""
					(reference "#PWR037")
					(unit 1)
				)
			)
		)
	)
	(symbol
		(lib_id "antmicroLEDIndicationDiscrete:LED_G_0603_KP-1608CGCK")
		(at 223.52 314.96 270)
		(mirror x)
		(unit 1)
		(exclude_from_sim no)
		(in_bom yes)
		(on_board yes)
		(dnp no)
		(property "Reference" "D3"
			(at 220.98 311.15 90)
			(effects
				(font
					(size 1.27 1.27)
					(thickness 0.15)
				)
				(justify right)
			)
		)
		(property "Value" "LED_G_0603_KP-1608CGCK"
			(at 220.98 309.8801 90)
			(effects
				(font
					(size 1.27 1.27)
					(thickness 0.15)
				)
				(justify right)
				(hide yes)
			)
		)
		(property "Footprint" "antmicro-footprints:LED_0603_1608Metric_G"
			(at 213.36 292.1 0)
			(effects
				(font
					(size 1.27 1.27)
					(thickness 0.15)
				)
				(justify left bottom)
				(hide yes)
			)
		)
		(property "Datasheet" "http://www.kingbright.com/attachments/file/psearch//000/00/00/KP-1608CGCK(Ver.23B).pdf"
			(at 210.82 292.1 0)
			(effects
				(font
					(size 1.27 1.27)
					(thickness 0.15)
				)
				(justify left bottom)
				(hide yes)
			)
		)
		(property "Description" ""
			(at 223.52 314.96 0)
			(effects
				(font
					(size 1.27 1.27)
				)
				(hide yes)
			)
		)
		(property "MPN" "KP-1608CGCK"
			(at 208.28 292.1 0)
			(effects
				(font
					(size 1.27 1.27)
					(thickness 0.15)
				)
				(justify left bottom)
				(hide yes)
			)
		)
		(property "Manufacturer" "Kingbright"
			(at 205.74 292.1 0)
			(effects
				(font
					(size 1.27 1.27)
					(thickness 0.15)
				)
				(justify left bottom)
				(hide yes)
			)
		)
		(property "License" "Apache-2.0"
			(at 200.66 292.1 0)
			(effects
				(font
					(size 1.27 1.27)
					(thickness 0.15)
				)
				(justify left bottom)
				(hide yes)
			)
		)
		(property "Author" "Antmicro"
			(at 203.2 292.1 0)
			(effects
				(font
					(size 1.27 1.27)
					(thickness 0.15)
				)
				(justify left bottom)
				(hide yes)
			)
		)
		(property "Color" "Green"
			(at 220.98 313.69 90)
			(effects
				(font
					(size 1.27 1.27)
				)
				(justify right)
			)
		)
		(pin "1"
		)
		(pin "2"
		)
		(instances
			(project "thunderbolt-gpu-adapter"
				(path ""
					(reference "D3")
					(unit 1)
				)
			)
		)
	)
	(symbol
		(lib_id "antmicroCapacitors0402:C_1u_0402")
		(at 93.98 360.68 90)
		(unit 1)
		(exclude_from_sim no)
		(in_bom yes)
		(on_board yes)
		(dnp no)
		(property "Reference" "C25"
			(at 94.615 356.235 90)
			(effects
				(font
					(size 1.27 1.27)
					(thickness 0.15)
				)
				(justify right)
			)
		)
		(property "Value" "C_1u_0402"
			(at 104.14 340.36 0)
			(effects
				(font
					(size 1.27 1.27)
					(thickness 0.15)
				)
				(justify left bottom)
				(hide yes)
			)
		)
		(property "Footprint" "antmicro-footprints:C_0402_1005Metric"
			(at 106.68 340.36 0)
			(effects
				(font
					(size 1.27 1.27)
					(thickness 0.15)
				)
				(justify left bottom)
				(hide yes)
			)
		)
		(property "Datasheet" "https://product.tdk.com/en/search/capacitor/ceramic/mlcc/info?part_no=C1005X6S1A105K050BC"
			(at 109.22 340.36 0)
			(effects
				(font
					(size 1.27 1.27)
					(thickness 0.15)
				)
				(justify left bottom)
				(hide yes)
			)
		)
		(property "Description" ""
			(at 93.98 360.68 0)
			(effects
				(font
					(size 1.27 1.27)
				)
				(hide yes)
			)
		)
		(property "MPN" "C1005X6S1A105K050BC"
			(at 111.76 340.36 0)
			(effects
				(font
					(size 1.27 1.27)
					(thickness 0.15)
				)
				(justify left bottom)
				(hide yes)
			)
		)
		(property "Manufacturer" "TDK"
			(at 114.3 340.36 0)
			(effects
				(font
					(size 1.27 1.27)
					(thickness 0.15)
				)
				(justify left bottom)
				(hide yes)
			)
		)
		(property "License" "Apache-2.0"
			(at 116.84 340.36 0)
			(effects
				(font
					(size 1.27 1.27)
					(thickness 0.15)
				)
				(justify left bottom)
				(hide yes)
			)
		)
		(property "Val" "1u"
			(at 94.615 360.045 90)
			(effects
				(font
					(size 1.27 1.27)
					(thickness 0.15)
				)
				(justify right)
			)
		)
		(property "Voltage" ""
			(at 121.92 340.36 0)
			(effects
				(font
					(size 1.27 1.27)
				)
				(justify left bottom)
				(hide yes)
			)
		)
		(property "Dielectric" ""
			(at 124.46 340.36 0)
			(effects
				(font
					(size 1.27 1.27)
				)
				(justify left bottom)
				(hide yes)
			)
		)
		(property "Author" "Antmicro"
			(at 119.38 340.36 0)
			(effects
				(font
					(size 1.27 1.27)
					(thickness 0.15)
				)
				(justify left bottom)
				(hide yes)
			)
		)
		(pin "1"
		)
		(pin "2"
		)
		(instances
			(project "thunderbolt-gpu-adapter"
				(path ""
					(reference "C25")
					(unit 1)
				)
			)
		)
	)
	(symbol
		(lib_id "antmicropower:GND")
		(at 247.65 95.25 0)
		(unit 1)
		(exclude_from_sim no)
		(in_bom yes)
		(on_board yes)
		(dnp no)
		(property "Reference" "#PWR0168"
			(at 247.65 101.6 0)
			(effects
				(font
					(size 1.27 1.27)
				)
				(hide yes)
			)
		)
		(property "Value" "GND"
			(at 247.65 99.06 0)
			(effects
				(font
					(size 1.27 1.27)
				)
			)
		)
		(property "Footprint" ""
			(at 247.65 95.25 0)
			(effects
				(font
					(size 1.27 1.27)
				)
				(hide yes)
			)
		)
		(property "Datasheet" ""
			(at 247.65 95.25 0)
			(effects
				(font
					(size 1.27 1.27)
				)
				(hide yes)
			)
		)
		(property "Description" ""
			(at 247.65 95.25 0)
			(effects
				(font
					(size 1.27 1.27)
				)
				(hide yes)
			)
		)
		(property "Author" "Antmicro"
			(at 256.54 102.87 0)
			(effects
				(font
					(size 1.27 1.27)
					(thickness 0.15)
				)
				(justify left bottom)
				(hide yes)
			)
		)
		(property "License" "Apache-2.0"
			(at 256.54 105.41 0)
			(effects
				(font
					(size 1.27 1.27)
					(thickness 0.15)
				)
				(justify left bottom)
				(hide yes)
			)
		)
		(pin "1"
		)
		(instances
			(project "thunderbolt-gpu-adapter"
				(path ""
					(reference "#PWR0168")
					(unit 1)
				)
			)
		)
	)
	(symbol
		(lib_id "antmicroCapacitors0402:C_220p_0402")
		(at 162.56 87.63 90)
		(unit 1)
		(exclude_from_sim no)
		(in_bom yes)
		(on_board yes)
		(dnp no)
		(fields_autoplaced yes)
		(property "Reference" "C45"
			(at 165.1 83.8136 90)
			(effects
				(font
					(size 1.27 1.27)
					(thickness 0.15)
				)
				(justify right)
			)
		)
		(property "Value" "C_220p_0402"
			(at 172.72 67.31 0)
			(effects
				(font
					(size 1.27 1.27)
					(thickness 0.15)
				)
				(justify left bottom)
				(hide yes)
			)
		)
		(property "Footprint" "antmicro-footprints:C_0402_1005Metric"
			(at 175.26 67.31 0)
			(effects
				(font
					(size 1.27 1.27)
					(thickness 0.15)
				)
				(justify left bottom)
				(hide yes)
			)
		)
		(property "Datasheet" "https://spicat.kyocera-avx.com/product/mlcc/chartview/04025C221JAT2A/"
			(at 177.8 67.31 0)
			(effects
				(font
					(size 1.27 1.27)
					(thickness 0.15)
				)
				(justify left bottom)
				(hide yes)
			)
		)
		(property "Description" ""
			(at 162.56 87.63 0)
			(effects
				(font
					(size 1.27 1.27)
				)
				(hide yes)
			)
		)
		(property "MPN" "04025C221JAT2A"
			(at 180.34 67.31 0)
			(effects
				(font
					(size 1.27 1.27)
					(thickness 0.15)
				)
				(justify left bottom)
				(hide yes)
			)
		)
		(property "Manufacturer" "KYOCERA AVX"
			(at 182.88 67.31 0)
			(effects
				(font
					(size 1.27 1.27)
					(thickness 0.15)
				)
				(justify left bottom)
				(hide yes)
			)
		)
		(property "License" "Apache-2.0"
			(at 185.42 67.31 0)
			(effects
				(font
					(size 1.27 1.27)
					(thickness 0.15)
				)
				(justify left bottom)
				(hide yes)
			)
		)
		(property "Val" "220p"
			(at 165.1 86.3536 90)
			(effects
				(font
					(size 1.27 1.27)
					(thickness 0.15)
				)
				(justify right)
			)
		)
		(property "Voltage" ""
			(at 190.5 67.31 0)
			(effects
				(font
					(size 1.27 1.27)
				)
				(justify left bottom)
				(hide yes)
			)
		)
		(property "Dielectric" ""
			(at 193.04 67.31 0)
			(effects
				(font
					(size 1.27 1.27)
				)
				(justify left bottom)
				(hide yes)
			)
		)
		(property "Author" "Antmicro"
			(at 187.96 67.31 0)
			(effects
				(font
					(size 1.27 1.27)
					(thickness 0.15)
				)
				(justify left bottom)
				(hide yes)
			)
		)
		(pin "1"
		)
		(pin "2"
		)
		(instances
			(project "thunderbolt-gpu-adapter"
				(path ""
					(reference "C45")
					(unit 1)
				)
			)
		)
	)
	(symbol
		(lib_id "antmicroResistors0402:R_100k_0402")
		(at 135.89 153.67 0)
		(unit 1)
		(exclude_from_sim no)
		(in_bom yes)
		(on_board yes)
		(dnp no)
		(property "Reference" "R34"
			(at 133.985 152.4 0)
			(effects
				(font
					(size 1.27 1.27)
					(thickness 0.15)
				)
			)
		)
		(property "Value" "R_100k_0402"
			(at 156.21 166.37 0)
			(effects
				(font
					(size 1.27 1.27)
					(thickness 0.15)
				)
				(justify left bottom)
				(hide yes)
			)
		)
		(property "Footprint" "antmicro-footprints:R_0402_1005Metric"
			(at 156.21 168.91 0)
			(effects
				(font
					(size 1.27 1.27)
					(thickness 0.15)
				)
				(justify left bottom)
				(hide yes)
			)
		)
		(property "Datasheet" "https://www.bourns.com/docs/product-datasheets/cr.pdf"
			(at 156.21 171.45 0)
			(effects
				(font
					(size 1.27 1.27)
					(thickness 0.15)
				)
				(justify left bottom)
				(hide yes)
			)
		)
		(property "Description" ""
			(at 135.89 153.67 0)
			(effects
				(font
					(size 1.27 1.27)
				)
				(hide yes)
			)
		)
		(property "MPN" "CR0402-FX-1003GLF"
			(at 156.21 173.99 0)
			(effects
				(font
					(size 1.27 1.27)
					(thickness 0.15)
				)
				(justify left bottom)
				(hide yes)
			)
		)
		(property "Manufacturer" "Bourns"
			(at 156.21 176.53 0)
			(effects
				(font
					(size 1.27 1.27)
					(thickness 0.15)
				)
				(justify left bottom)
				(hide yes)
			)
		)
		(property "License" "Apache-2.0"
			(at 156.21 179.07 0)
			(effects
				(font
					(size 1.27 1.27)
					(thickness 0.15)
				)
				(justify left bottom)
				(hide yes)
			)
		)
		(property "Val" "100k"
			(at 142.875 152.4 0)
			(effects
				(font
					(size 1.27 1.27)
					(thickness 0.15)
				)
			)
		)
		(property "Tolerance" "1%"
			(at 156.21 163.83 0)
			(effects
				(font
					(size 1.27 1.27)
				)
				(justify left bottom)
				(hide yes)
			)
		)
		(property "Author" "Antmicro"
			(at 156.21 181.61 0)
			(effects
				(font
					(size 1.27 1.27)
					(thickness 0.15)
				)
				(justify left bottom)
				(hide yes)
			)
		)
		(pin "1"
		)
		(pin "2"
		)
		(instances
			(project "thunderbolt-gpu-adapter"
				(path ""
					(reference "R34")
					(unit 1)
				)
			)
		)
	)
	(symbol
		(lib_id "antmicroCapacitors0402:C_2u2_0402")
		(at 133.35 59.69 0)
		(unit 1)
		(exclude_from_sim no)
		(in_bom yes)
		(on_board yes)
		(dnp no)
		(property "Reference" "C35"
			(at 138.43 58.42 0)
			(effects
				(font
					(size 1.27 1.27)
					(thickness 0.15)
				)
			)
		)
		(property "Value" "C_2u2_0402"
			(at 153.67 69.85 0)
			(effects
				(font
					(size 1.27 1.27)
					(thickness 0.15)
				)
				(justify left bottom)
				(hide yes)
			)
		)
		(property "Footprint" "antmicro-footprints:C_0402_1005Metric"
			(at 153.67 72.39 0)
			(effects
				(font
					(size 1.27 1.27)
					(thickness 0.15)
				)
				(justify left bottom)
				(hide yes)
			)
		)
		(property "Datasheet" "https://product.tdk.com/en/search/capacitor/ceramic/mlcc/info?part_no=C1005X5R1A225K050BC"
			(at 153.67 74.93 0)
			(effects
				(font
					(size 1.27 1.27)
					(thickness 0.15)
				)
				(justify left bottom)
				(hide yes)
			)
		)
		(property "Description" ""
			(at 133.35 59.69 0)
			(effects
				(font
					(size 1.27 1.27)
				)
				(hide yes)
			)
		)
		(property "MPN" "C1005X5R1A225K050BC"
			(at 153.67 77.47 0)
			(effects
				(font
					(size 1.27 1.27)
					(thickness 0.15)
				)
				(justify left bottom)
				(hide yes)
			)
		)
		(property "Manufacturer" "TDK"
			(at 153.67 80.01 0)
			(effects
				(font
					(size 1.27 1.27)
					(thickness 0.15)
				)
				(justify left bottom)
				(hide yes)
			)
		)
		(property "License" "Apache-2.0"
			(at 153.67 82.55 0)
			(effects
				(font
					(size 1.27 1.27)
					(thickness 0.15)
				)
				(justify left bottom)
				(hide yes)
			)
		)
		(property "Val" "2u2"
			(at 138.43 60.96 0)
			(effects
				(font
					(size 1.27 1.27)
					(thickness 0.15)
				)
			)
		)
		(property "Voltage" ""
			(at 153.67 87.63 0)
			(effects
				(font
					(size 1.27 1.27)
				)
				(justify left bottom)
				(hide yes)
			)
		)
		(property "Dielectric" ""
			(at 153.67 90.17 0)
			(effects
				(font
					(size 1.27 1.27)
				)
				(justify left bottom)
				(hide yes)
			)
		)
		(property "Author" "Antmicro"
			(at 153.67 85.09 0)
			(effects
				(font
					(size 1.27 1.27)
					(thickness 0.15)
				)
				(justify left bottom)
				(hide yes)
			)
		)
		(pin "1"
		)
		(pin "2"
		)
		(instances
			(project "thunderbolt-gpu-adapter"
				(path ""
					(reference "C35")
					(unit 1)
				)
			)
		)
	)
	(symbol
		(lib_id "antmicroShuntsJumpers:Net-Tie_P0.127mm")
		(at 250.19 205.74 270)
		(unit 1)
		(exclude_from_sim no)
		(in_bom no)
		(on_board yes)
		(dnp no)
		(property "Reference" "TP11"
			(at 250.825 208.915 90)
			(effects
				(font
					(size 1.27 1.27)
					(thickness 0.15)
				)
				(justify left)
			)
		)
		(property "Value" "Net-Tie_P0.127mm"
			(at 252.095 210.185 90)
			(effects
				(font
					(size 1.27 1.27)
					(thickness 0.15)
				)
				(justify left)
				(hide yes)
			)
		)
		(property "Footprint" "antmicro-footprints:NetTie-2_SMD_Pad0.127mm"
			(at 237.49 227.33 0)
			(effects
				(font
					(size 1.27 1.27)
					(thickness 0.15)
				)
				(justify left bottom)
				(hide yes)
			)
		)
		(property "Datasheet" ""
			(at 234.95 227.33 0)
			(effects
				(font
					(size 1.27 1.27)
					(thickness 0.15)
				)
				(justify left bottom)
				(hide yes)
			)
		)
		(property "Description" ""
			(at 250.19 205.74 0)
			(effects
				(font
					(size 1.27 1.27)
				)
				(hide yes)
			)
		)
		(property "MPN" ""
			(at 240.03 227.33 0)
			(effects
				(font
					(size 1.27 1.27)
					(thickness 0.15)
				)
				(justify left bottom)
			)
		)
		(property "Manufacturer" ""
			(at 232.41 227.33 0)
			(effects
				(font
					(size 1.27 1.27)
					(thickness 0.15)
				)
				(justify left bottom)
				(hide yes)
			)
		)
		(property "Author" "Antmicro"
			(at 229.87 227.33 0)
			(effects
				(font
					(size 1.27 1.27)
					(thickness 0.15)
				)
				(justify left bottom)
				(hide yes)
			)
		)
		(property "License" "Apache-2.0"
			(at 227.33 227.33 0)
			(effects
				(font
					(size 1.27 1.27)
					(thickness 0.15)
				)
				(justify left bottom)
				(hide yes)
			)
		)
		(pin "1"
		)
		(pin "2"
		)
		(instances
			(project "thunderbolt-gpu-adapter"
				(path ""
					(reference "TP11")
					(unit 1)
				)
			)
		)
	)
	(symbol
		(lib_id "antmicroTestPoints:TP_0.75mm_SMD")
		(at 127 231.14 0)
		(mirror y)
		(unit 1)
		(exclude_from_sim no)
		(in_bom no)
		(on_board yes)
		(dnp no)
		(property "Reference" "TP6"
			(at 123.19 231.14 0)
			(effects
				(font
					(size 1.27 1.27)
					(thickness 0.15)
				)
				(justify left)
			)
		)
		(property "Value" "TP_0.75mm_SMD"
			(at 121.92 231.1399 0)
			(effects
				(font
					(size 1.27 1.27)
					(thickness 0.15)
				)
				(justify left bottom)
				(hide yes)
			)
		)
		(property "Footprint" "antmicro-footprints:TP_SMD_0.75mm"
			(at 111.76 241.3 0)
			(effects
				(font
					(size 1.27 1.27)
					(thickness 0.15)
				)
				(justify left bottom)
				(hide yes)
			)
		)
		(property "Datasheet" ""
			(at 111.76 243.84 0)
			(effects
				(font
					(size 1.27 1.27)
					(thickness 0.15)
				)
				(justify left bottom)
				(hide yes)
			)
		)
		(property "Description" ""
			(at 127 231.14 0)
			(effects
				(font
					(size 1.27 1.27)
				)
				(hide yes)
			)
		)
		(property "License" "Apache-2.0"
			(at 111.76 248.92 0)
			(effects
				(font
					(size 1.27 1.27)
					(thickness 0.15)
				)
				(justify left bottom)
				(hide yes)
			)
		)
		(property "Manufacturer" ""
			(at 121.92 233.6799 0)
			(effects
				(font
					(size 1.27 1.27)
					(thickness 0.15)
				)
				(justify left bottom)
				(hide yes)
			)
		)
		(property "MPN" ""
			(at 127 231.14 0)
			(effects
				(font
					(size 1.27 1.27)
					(thickness 0.15)
				)
				(justify left bottom)
				(hide yes)
			)
		)
		(property "Author" "Antmicro"
			(at 111.76 246.38 0)
			(effects
				(font
					(size 1.27 1.27)
					(thickness 0.15)
				)
				(justify left bottom)
				(hide yes)
			)
		)
		(pin "1"
		)
		(instances
			(project "thunderbolt-gpu-adapter"
				(path ""
					(reference "TP6")
					(unit 1)
				)
			)
		)
	)
	(symbol
		(lib_id "antmicroCapacitorsmisc:C_10u_0805_35V")
		(at 83.82 392.43 90)
		(unit 1)
		(exclude_from_sim no)
		(in_bom yes)
		(on_board yes)
		(dnp no)
		(property "Reference" "C128"
			(at 76.2 388.62 90)
			(effects
				(font
					(size 1.27 1.27)
					(thickness 0.15)
				)
				(justify right)
			)
		)
		(property "Value" "C_10u_0805_35V"
			(at 93.98 372.11 0)
			(effects
				(font
					(size 1.27 1.27)
					(thickness 0.15)
				)
				(justify left bottom)
				(hide yes)
			)
		)
		(property "Footprint" "antmicro-footprints:C_0805_2012Metric"
			(at 96.52 372.11 0)
			(effects
				(font
					(size 1.27 1.27)
					(thickness 0.15)
				)
				(justify left bottom)
				(hide yes)
			)
		)
		(property "Datasheet" "https://www.murata.com/products/productdetail?partno=GRM21BR6YA106KE43%23"
			(at 99.06 372.11 0)
			(effects
				(font
					(size 1.27 1.27)
					(thickness 0.15)
				)
				(justify left bottom)
				(hide yes)
			)
		)
		(property "Description" ""
			(at 83.82 392.43 0)
			(effects
				(font
					(size 1.27 1.27)
				)
				(hide yes)
			)
		)
		(property "MPN" "GRM21BR6YA106KE43L"
			(at 101.6 372.11 0)
			(effects
				(font
					(size 1.27 1.27)
					(thickness 0.15)
				)
				(justify left bottom)
				(hide yes)
			)
		)
		(property "Manufacturer" "Murata"
			(at 104.14 372.11 0)
			(effects
				(font
					(size 1.27 1.27)
					(thickness 0.15)
				)
				(justify left bottom)
				(hide yes)
			)
		)
		(property "License" "Apache-2.0"
			(at 106.68 372.11 0)
			(effects
				(font
					(size 1.27 1.27)
					(thickness 0.15)
				)
				(justify left bottom)
				(hide yes)
			)
		)
		(property "Val" "10u"
			(at 76.2 391.16 90)
			(effects
				(font
					(size 1.27 1.27)
					(thickness 0.15)
				)
				(justify right)
			)
		)
		(property "Voltage" "35V"
			(at 111.76 372.11 0)
			(effects
				(font
					(size 1.27 1.27)
				)
				(justify left bottom)
				(hide yes)
			)
		)
		(property "Dielectric" ""
			(at 114.3 372.11 0)
			(effects
				(font
					(size 1.27 1.27)
				)
				(justify left bottom)
				(hide yes)
			)
		)
		(property "Author" "Antmicro"
			(at 109.22 372.11 0)
			(effects
				(font
					(size 1.27 1.27)
					(thickness 0.15)
				)
				(justify left bottom)
				(hide yes)
			)
		)
		(pin "1"
		)
		(pin "2"
		)
		(instances
			(project "thunderbolt-gpu-adapter"
				(path ""
					(reference "C128")
					(unit 1)
				)
			)
		)
	)
	(symbol
		(lib_id "antmicroResistors0402:R_3k3_0402")
		(at 64.77 82.55 0)
		(unit 1)
		(exclude_from_sim no)
		(in_bom yes)
		(on_board yes)
		(dnp no)
		(property "Reference" "R14"
			(at 63.5 81.28 0)
			(effects
				(font
					(size 1.27 1.27)
					(thickness 0.15)
				)
			)
		)
		(property "Value" "R_3k3_0402"
			(at 85.09 95.25 0)
			(effects
				(font
					(size 1.27 1.27)
					(thickness 0.15)
				)
				(justify left bottom)
				(hide yes)
			)
		)
		(property "Footprint" "antmicro-footprints:R_0402_1005Metric"
			(at 85.09 97.79 0)
			(effects
				(font
					(size 1.27 1.27)
					(thickness 0.15)
				)
				(justify left bottom)
				(hide yes)
			)
		)
		(property "Datasheet" "https://www.bourns.com/docs/product-datasheets/cr.pdf"
			(at 85.09 100.33 0)
			(effects
				(font
					(size 1.27 1.27)
					(thickness 0.15)
				)
				(justify left bottom)
				(hide yes)
			)
		)
		(property "Description" ""
			(at 64.77 82.55 0)
			(effects
				(font
					(size 1.27 1.27)
				)
				(hide yes)
			)
		)
		(property "MPN" "CR0402-FX-3301GLF"
			(at 85.09 102.87 0)
			(effects
				(font
					(size 1.27 1.27)
					(thickness 0.15)
				)
				(justify left bottom)
				(hide yes)
			)
		)
		(property "Manufacturer" "Bourns"
			(at 85.09 105.41 0)
			(effects
				(font
					(size 1.27 1.27)
					(thickness 0.15)
				)
				(justify left bottom)
				(hide yes)
			)
		)
		(property "License" "Apache-2.0"
			(at 85.09 107.95 0)
			(effects
				(font
					(size 1.27 1.27)
					(thickness 0.15)
				)
				(justify left bottom)
				(hide yes)
			)
		)
		(property "Val" "3k3"
			(at 71.12 81.28 0)
			(effects
				(font
					(size 1.27 1.27)
					(thickness 0.15)
				)
			)
		)
		(property "Tolerance" "1%"
			(at 85.09 92.71 0)
			(effects
				(font
					(size 1.27 1.27)
				)
				(justify left bottom)
				(hide yes)
			)
		)
		(property "Author" "Antmicro"
			(at 85.09 110.49 0)
			(effects
				(font
					(size 1.27 1.27)
					(thickness 0.15)
				)
				(justify left bottom)
				(hide yes)
			)
		)
		(pin "1"
		)
		(pin "2"
		)
		(instances
			(project "thunderbolt-gpu-adapter"
				(path ""
					(reference "R14")
					(unit 1)
				)
			)
		)
	)
	(symbol
		(lib_id "antmicroPMICORControllersIdealDiodes:DZDH0401DW")
		(at 233.68 275.59 0)
		(unit 1)
		(exclude_from_sim no)
		(in_bom yes)
		(on_board yes)
		(dnp no)
		(fields_autoplaced yes)
		(property "Reference" "Q3"
			(at 241.935 269.24 0)
			(effects
				(font
					(size 1.524 1.524)
				)
			)
		)
		(property "Value" "DZDH0401DW"
			(at 264.16 283.21 0)
			(effects
				(font
					(size 1.27 1.27)
					(thickness 0.15)
				)
				(justify left bottom)
				(hide yes)
			)
		)
		(property "Footprint" "antmicro-footprints:SOT-363"
			(at 264.16 285.75 0)
			(effects
				(font
					(size 1.27 1.27)
					(thickness 0.15)
				)
				(justify left bottom)
				(hide yes)
			)
		)
		(property "Datasheet" "https://www.mouser.com/datasheet/2/115/DIOD_S_A0011803041_1-2543705.pdf"
			(at 264.16 288.29 0)
			(effects
				(font
					(size 1.27 1.27)
					(thickness 0.15)
				)
				(justify left bottom)
				(hide yes)
			)
		)
		(property "Description" ""
			(at 233.68 275.59 0)
			(effects
				(font
					(size 1.27 1.27)
				)
				(hide yes)
			)
		)
		(property "MPN" "DZDH0401DW"
			(at 241.935 271.78 0)
			(effects
				(font
					(size 1.27 1.27)
					(thickness 0.15)
				)
			)
		)
		(property "Manufacturer" "Diodes Incorporated"
			(at 264.16 293.37 0)
			(effects
				(font
					(size 1.27 1.27)
					(thickness 0.15)
				)
				(justify left bottom)
				(hide yes)
			)
		)
		(property "Author" "Antmicro"
			(at 264.16 295.91 0)
			(effects
				(font
					(size 1.27 1.27)
					(thickness 0.15)
				)
				(justify left bottom)
				(hide yes)
			)
		)
		(property "License" "Apache-2.0"
			(at 264.16 298.45 0)
			(effects
				(font
					(size 1.27 1.27)
					(thickness 0.15)
				)
				(justify left bottom)
				(hide yes)
			)
		)
		(pin "2"
		)
		(pin "3"
		)
		(pin "4"
		)
		(pin "6"
		)
		(instances
			(project "thunderbolt-gpu-adapter"
				(path ""
					(reference "Q3")
					(unit 1)
				)
			)
		)
	)
	(symbol
		(lib_id "antmicroCapacitors0603:C_22u_16V_0603")
		(at 55.88 266.7 90)
		(unit 1)
		(exclude_from_sim no)
		(in_bom yes)
		(on_board yes)
		(dnp no)
		(fields_autoplaced yes)
		(property "Reference" "C122"
			(at 58.42 262.8836 90)
			(effects
				(font
					(size 1.27 1.27)
					(thickness 0.15)
				)
				(justify right)
			)
		)
		(property "Value" "C_22u_16V_0603"
			(at 66.04 246.38 0)
			(effects
				(font
					(size 1.27 1.27)
					(thickness 0.15)
				)
				(justify left bottom)
				(hide yes)
			)
		)
		(property "Footprint" "antmicro-footprints:C_0603_1608Metric"
			(at 68.58 246.38 0)
			(effects
				(font
					(size 1.27 1.27)
					(thickness 0.15)
				)
				(justify left bottom)
				(hide yes)
			)
		)
		(property "Datasheet" "https://product.samsungsem.com/mlcc/CL10A226MO7JZN.do"
			(at 71.12 246.38 0)
			(effects
				(font
					(size 1.27 1.27)
					(thickness 0.15)
				)
				(justify left bottom)
				(hide yes)
			)
		)
		(property "Description" ""
			(at 55.88 266.7 0)
			(effects
				(font
					(size 1.27 1.27)
				)
				(hide yes)
			)
		)
		(property "MPN" "CL10A226MO7JZNC"
			(at 73.66 246.38 0)
			(effects
				(font
					(size 1.27 1.27)
					(thickness 0.15)
				)
				(justify left bottom)
				(hide yes)
			)
		)
		(property "Manufacturer" "Samsung Electro-Mechanics"
			(at 76.2 246.38 0)
			(effects
				(font
					(size 1.27 1.27)
					(thickness 0.15)
				)
				(justify left bottom)
				(hide yes)
			)
		)
		(property "License" "Apache-2.0"
			(at 78.74 246.38 0)
			(effects
				(font
					(size 1.27 1.27)
					(thickness 0.15)
				)
				(justify left bottom)
				(hide yes)
			)
		)
		(property "Val" "22u"
			(at 58.42 265.4236 90)
			(effects
				(font
					(size 1.27 1.27)
					(thickness 0.15)
				)
				(justify right)
			)
		)
		(property "Voltage" "16V"
			(at 83.82 246.38 0)
			(effects
				(font
					(size 1.27 1.27)
				)
				(justify left bottom)
				(hide yes)
			)
		)
		(property "Dielectric" ""
			(at 86.36 246.38 0)
			(effects
				(font
					(size 1.27 1.27)
				)
				(justify left bottom)
				(hide yes)
			)
		)
		(property "Author" "Antmicro"
			(at 81.28 246.38 0)
			(effects
				(font
					(size 1.27 1.27)
					(thickness 0.15)
				)
				(justify left bottom)
				(hide yes)
			)
		)
		(pin "1"
		)
		(pin "2"
		)
		(instances
			(project "thunderbolt-gpu-adapter"
				(path ""
					(reference "C122")
					(unit 1)
				)
			)
		)
	)
	(symbol
		(lib_id "antmicropower:PWR_FLAG")
		(at 114.3 384.81 0)
		(unit 1)
		(exclude_from_sim no)
		(in_bom yes)
		(on_board yes)
		(dnp no)
		(fields_autoplaced yes)
		(property "Reference" "#FLG0102"
			(at 114.3 382.905 0)
			(effects
				(font
					(size 1.27 1.27)
				)
				(hide yes)
			)
		)
		(property "Value" "PWR_FLAG"
			(at 114.3 379.73 0)
			(effects
				(font
					(size 1.27 1.27)
				)
			)
		)
		(property "Footprint" ""
			(at 114.3 384.81 0)
			(effects
				(font
					(size 1.27 1.27)
				)
				(hide yes)
			)
		)
		(property "Datasheet" ""
			(at 114.3 384.81 0)
			(effects
				(font
					(size 1.27 1.27)
				)
				(hide yes)
			)
		)
		(property "Description" ""
			(at 114.3 384.81 0)
			(effects
				(font
					(size 1.27 1.27)
				)
				(hide yes)
			)
		)
		(pin "1"
		)
		(instances
			(project "thunderbolt-gpu-adapter"
				(path ""
					(reference "#FLG0102")
					(unit 1)
				)
			)
		)
	)
	(symbol
		(lib_id "antmicroTransistorsBipolarSingle:BC817-25W")
		(at 59.69 242.57 0)
		(unit 1)
		(exclude_from_sim no)
		(in_bom yes)
		(on_board yes)
		(dnp no)
		(fields_autoplaced yes)
		(property "Reference" "Q2"
			(at 68.58 241.3 0)
			(effects
				(font
					(size 1.27 1.27)
					(thickness 0.15)
				)
				(justify left)
			)
		)
		(property "Value" "BC817-25W"
			(at 82.55 245.11 0)
			(effects
				(font
					(size 1.27 1.27)
					(thickness 0.15)
				)
				(justify left bottom)
				(hide yes)
			)
		)
		(property "Footprint" "antmicro-footprints:SOT-323"
			(at 82.55 247.65 0)
			(effects
				(font
					(size 1.27 1.27)
					(thickness 0.15)
				)
				(justify left bottom)
				(hide yes)
			)
		)
		(property "Datasheet" "https://assets.nexperia.com/documents/data-sheet/BC817W_SER.pdf"
			(at 82.55 250.19 0)
			(effects
				(font
					(size 1.27 1.27)
					(thickness 0.15)
				)
				(justify left bottom)
				(hide yes)
			)
		)
		(property "Description" ""
			(at 59.69 242.57 0)
			(effects
				(font
					(size 1.27 1.27)
				)
				(hide yes)
			)
		)
		(property "MPN" "BC817-25W,115"
			(at 68.58 243.84 0)
			(effects
				(font
					(size 1.27 1.27)
					(thickness 0.15)
				)
				(justify left)
			)
		)
		(property "Manufacturer" "Nexperia"
			(at 82.55 255.27 0)
			(effects
				(font
					(size 1.27 1.27)
					(thickness 0.15)
				)
				(justify left bottom)
				(hide yes)
			)
		)
		(property "License" "Apache-2.0"
			(at 82.55 260.35 0)
			(effects
				(font
					(size 1.27 1.27)
					(thickness 0.15)
				)
				(justify left bottom)
				(hide yes)
			)
		)
		(property "Author" "Antmicro"
			(at 82.55 257.81 0)
			(effects
				(font
					(size 1.27 1.27)
					(thickness 0.15)
				)
				(justify left bottom)
				(hide yes)
			)
		)
		(pin "1"
		)
		(pin "2"
		)
		(pin "3"
		)
		(instances
			(project "thunderbolt-gpu-adapter"
				(path ""
					(reference "Q2")
					(unit 1)
				)
			)
		)
	)
	(symbol
		(lib_id "antmicropower:GND")
		(at 181.61 364.49 0)
		(unit 1)
		(exclude_from_sim no)
		(in_bom yes)
		(on_board yes)
		(dnp no)
		(fields_autoplaced yes)
		(property "Reference" "#PWR065"
			(at 181.61 370.84 0)
			(effects
				(font
					(size 1.27 1.27)
				)
				(hide yes)
			)
		)
		(property "Value" "GND"
			(at 181.61 368.3 0)
			(effects
				(font
					(size 1.27 1.27)
				)
			)
		)
		(property "Footprint" ""
			(at 181.61 364.49 0)
			(effects
				(font
					(size 1.27 1.27)
				)
				(hide yes)
			)
		)
		(property "Datasheet" ""
			(at 181.61 364.49 0)
			(effects
				(font
					(size 1.27 1.27)
				)
				(hide yes)
			)
		)
		(property "Description" ""
			(at 181.61 364.49 0)
			(effects
				(font
					(size 1.27 1.27)
				)
				(hide yes)
			)
		)
		(property "Author" "Antmicro"
			(at 190.5 372.11 0)
			(effects
				(font
					(size 1.27 1.27)
					(thickness 0.15)
				)
				(justify left bottom)
				(hide yes)
			)
		)
		(property "License" "Apache-2.0"
			(at 190.5 374.65 0)
			(effects
				(font
					(size 1.27 1.27)
					(thickness 0.15)
				)
				(justify left bottom)
				(hide yes)
			)
		)
		(pin "1"
		)
		(instances
			(project "thunderbolt-gpu-adapter"
				(path ""
					(reference "#PWR065")
					(unit 1)
				)
			)
		)
	)
	(symbol
		(lib_id "antmicroResistors0402:R_100k_0402")
		(at 123.19 257.81 90)
		(unit 1)
		(exclude_from_sim no)
		(in_bom yes)
		(on_board yes)
		(dnp yes)
		(property "Reference" "R24"
			(at 120.65 254 90)
			(effects
				(font
					(size 1.27 1.27)
					(thickness 0.15)
				)
				(justify left)
			)
		)
		(property "Value" "R_100k_0402"
			(at 135.89 237.49 0)
			(effects
				(font
					(size 1.27 1.27)
					(thickness 0.15)
				)
				(justify left bottom)
				(hide yes)
			)
		)
		(property "Footprint" "antmicro-footprints:R_0402_1005Metric"
			(at 138.43 237.49 0)
			(effects
				(font
					(size 1.27 1.27)
					(thickness 0.15)
				)
				(justify left bottom)
				(hide yes)
			)
		)
		(property "Datasheet" "https://www.bourns.com/docs/product-datasheets/cr.pdf"
			(at 140.97 237.49 0)
			(effects
				(font
					(size 1.27 1.27)
					(thickness 0.15)
				)
				(justify left bottom)
				(hide yes)
			)
		)
		(property "Description" ""
			(at 123.19 257.81 0)
			(effects
				(font
					(size 1.27 1.27)
				)
				(hide yes)
			)
		)
		(property "MPN" "CR0402-FX-1003GLF"
			(at 143.51 237.49 0)
			(effects
				(font
					(size 1.27 1.27)
					(thickness 0.15)
				)
				(justify left bottom)
				(hide yes)
			)
		)
		(property "Manufacturer" "Bourns"
			(at 146.05 237.49 0)
			(effects
				(font
					(size 1.27 1.27)
					(thickness 0.15)
				)
				(justify left bottom)
				(hide yes)
			)
		)
		(property "License" "Apache-2.0"
			(at 148.59 237.49 0)
			(effects
				(font
					(size 1.27 1.27)
					(thickness 0.15)
				)
				(justify left bottom)
				(hide yes)
			)
		)
		(property "Val" "100k"
			(at 120.65 256.54 90)
			(effects
				(font
					(size 1.27 1.27)
					(thickness 0.15)
				)
				(justify left)
			)
		)
		(property "Tolerance" "1%"
			(at 133.35 237.49 0)
			(effects
				(font
					(size 1.27 1.27)
				)
				(justify left bottom)
				(hide yes)
			)
		)
		(property "Author" "Antmicro"
			(at 151.13 237.49 0)
			(effects
				(font
					(size 1.27 1.27)
					(thickness 0.15)
				)
				(justify left bottom)
				(hide yes)
			)
		)
		(pin "1"
		)
		(pin "2"
		)
		(instances
			(project "thunderbolt-gpu-adapter"
				(path ""
					(reference "R24")
					(unit 1)
				)
			)
		)
	)
	(symbol
		(lib_id "antmicroCapacitors0402:C_220n_0402")
		(at 133.35 171.45 90)
		(unit 1)
		(exclude_from_sim no)
		(in_bom yes)
		(on_board yes)
		(dnp no)
		(fields_autoplaced yes)
		(property "Reference" "C31"
			(at 136.525 167.6335 90)
			(effects
				(font
					(size 1.27 1.27)
					(thickness 0.15)
				)
				(justify right)
			)
		)
		(property "Value" "C_220n_0402"
			(at 143.51 151.13 0)
			(effects
				(font
					(size 1.27 1.27)
					(thickness 0.15)
				)
				(justify left bottom)
				(hide yes)
			)
		)
		(property "Footprint" "antmicro-footprints:C_0402_1005Metric"
			(at 146.05 151.13 0)
			(effects
				(font
					(size 1.27 1.27)
					(thickness 0.15)
				)
				(justify left bottom)
				(hide yes)
			)
		)
		(property "Datasheet" "https://www.yageo.com/en/Chart/Download/pdf/CC0402KRX5R6BB224"
			(at 148.59 151.13 0)
			(effects
				(font
					(size 1.27 1.27)
					(thickness 0.15)
				)
				(justify left bottom)
				(hide yes)
			)
		)
		(property "Description" ""
			(at 133.35 171.45 0)
			(effects
				(font
					(size 1.27 1.27)
				)
				(hide yes)
			)
		)
		(property "MPN" "CC0402KRX5R6BB224"
			(at 151.13 151.13 0)
			(effects
				(font
					(size 1.27 1.27)
					(thickness 0.15)
				)
				(justify left bottom)
				(hide yes)
			)
		)
		(property "Manufacturer" "YAGEO"
			(at 153.67 151.13 0)
			(effects
				(font
					(size 1.27 1.27)
					(thickness 0.15)
				)
				(justify left bottom)
				(hide yes)
			)
		)
		(property "License" "Apache-2.0"
			(at 156.21 151.13 0)
			(effects
				(font
					(size 1.27 1.27)
					(thickness 0.15)
				)
				(justify left bottom)
				(hide yes)
			)
		)
		(property "Val" "220n"
			(at 136.525 170.1735 90)
			(effects
				(font
					(size 1.27 1.27)
					(thickness 0.15)
				)
				(justify right)
			)
		)
		(property "Voltage" ""
			(at 161.29 151.13 0)
			(effects
				(font
					(size 1.27 1.27)
				)
				(justify left bottom)
				(hide yes)
			)
		)
		(property "Dielectric" ""
			(at 163.83 151.13 0)
			(effects
				(font
					(size 1.27 1.27)
				)
				(justify left bottom)
				(hide yes)
			)
		)
		(property "Author" "Antmicro"
			(at 158.75 151.13 0)
			(effects
				(font
					(size 1.27 1.27)
					(thickness 0.15)
				)
				(justify left bottom)
				(hide yes)
			)
		)
		(pin "1"
		)
		(pin "2"
		)
		(instances
			(project "thunderbolt-gpu-adapter"
				(path ""
					(reference "C31")
					(unit 1)
				)
			)
		)
	)
	(symbol
		(lib_id "antmicroResistors0402:R_100k_0402")
		(at 251.46 285.75 90)
		(unit 1)
		(exclude_from_sim no)
		(in_bom yes)
		(on_board yes)
		(dnp no)
		(fields_autoplaced yes)
		(property "Reference" "R95"
			(at 254 281.94 90)
			(effects
				(font
					(size 1.27 1.27)
					(thickness 0.15)
				)
				(justify right)
			)
		)
		(property "Value" "R_100k_0402"
			(at 264.16 265.43 0)
			(effects
				(font
					(size 1.27 1.27)
					(thickness 0.15)
				)
				(justify left bottom)
				(hide yes)
			)
		)
		(property "Footprint" "antmicro-footprints:R_0402_1005Metric"
			(at 266.7 265.43 0)
			(effects
				(font
					(size 1.27 1.27)
					(thickness 0.15)
				)
				(justify left bottom)
				(hide yes)
			)
		)
		(property "Datasheet" "https://www.bourns.com/docs/product-datasheets/cr.pdf"
			(at 269.24 265.43 0)
			(effects
				(font
					(size 1.27 1.27)
					(thickness 0.15)
				)
				(justify left bottom)
				(hide yes)
			)
		)
		(property "Description" ""
			(at 251.46 285.75 0)
			(effects
				(font
					(size 1.27 1.27)
				)
				(hide yes)
			)
		)
		(property "MPN" "CR0402-FX-1003GLF"
			(at 271.78 265.43 0)
			(effects
				(font
					(size 1.27 1.27)
					(thickness 0.15)
				)
				(justify left bottom)
				(hide yes)
			)
		)
		(property "Manufacturer" "Bourns"
			(at 274.32 265.43 0)
			(effects
				(font
					(size 1.27 1.27)
					(thickness 0.15)
				)
				(justify left bottom)
				(hide yes)
			)
		)
		(property "License" "Apache-2.0"
			(at 276.86 265.43 0)
			(effects
				(font
					(size 1.27 1.27)
					(thickness 0.15)
				)
				(justify left bottom)
				(hide yes)
			)
		)
		(property "Author" "Antmicro"
			(at 279.4 265.43 0)
			(effects
				(font
					(size 1.27 1.27)
					(thickness 0.15)
				)
				(justify left bottom)
				(hide yes)
			)
		)
		(property "Val" "100k"
			(at 254 284.48 90)
			(effects
				(font
					(size 1.27 1.27)
					(thickness 0.15)
				)
				(justify right)
			)
		)
		(property "Tolerance" "1%"
			(at 261.62 265.43 0)
			(effects
				(font
					(size 1.27 1.27)
				)
				(justify left bottom)
				(hide yes)
			)
		)
		(pin "1"
		)
		(pin "2"
		)
		(instances
			(project "thunderbolt-gpu-adapter"
				(path ""
					(reference "R95")
					(unit 1)
				)
			)
		)
	)
	(symbol
		(lib_id "antmicropower:PWR_FLAG")
		(at 158.75 205.74 180)
		(unit 1)
		(exclude_from_sim no)
		(in_bom yes)
		(on_board yes)
		(dnp no)
		(property "Reference" "#FLG02"
			(at 158.75 207.645 0)
			(effects
				(font
					(size 1.27 1.27)
				)
				(hide yes)
			)
		)
		(property "Value" "PWR_FLAG"
			(at 158.75 209.55 0)
			(effects
				(font
					(size 1.27 1.27)
				)
			)
		)
		(property "Footprint" ""
			(at 158.75 205.74 0)
			(effects
				(font
					(size 1.27 1.27)
				)
				(hide yes)
			)
		)
		(property "Datasheet" ""
			(at 158.75 205.74 0)
			(effects
				(font
					(size 1.27 1.27)
				)
				(hide yes)
			)
		)
		(property "Description" ""
			(at 158.75 205.74 0)
			(effects
				(font
					(size 1.27 1.27)
				)
				(hide yes)
			)
		)
		(pin "1"
		)
		(instances
			(project "thunderbolt-gpu-adapter"
				(path ""
					(reference "#FLG02")
					(unit 1)
				)
			)
		)
	)
	(symbol
		(lib_id "antmicroCapacitors0603:C_22u_16V_0603")
		(at 203.2 210.82 90)
		(unit 1)
		(exclude_from_sim no)
		(in_bom yes)
		(on_board yes)
		(dnp no)
		(fields_autoplaced yes)
		(property "Reference" "C40"
			(at 205.74 207.0036 90)
			(effects
				(font
					(size 1.27 1.27)
					(thickness 0.15)
				)
				(justify right)
			)
		)
		(property "Value" "C_22u_16V_0603"
			(at 213.36 190.5 0)
			(effects
				(font
					(size 1.27 1.27)
					(thickness 0.15)
				)
				(justify left bottom)
				(hide yes)
			)
		)
		(property "Footprint" "antmicro-footprints:C_0603_1608Metric"
			(at 215.9 190.5 0)
			(effects
				(font
					(size 1.27 1.27)
					(thickness 0.15)
				)
				(justify left bottom)
				(hide yes)
			)
		)
		(property "Datasheet" "https://product.samsungsem.com/mlcc/CL10A226MO7JZN.do"
			(at 218.44 190.5 0)
			(effects
				(font
					(size 1.27 1.27)
					(thickness 0.15)
				)
				(justify left bottom)
				(hide yes)
			)
		)
		(property "Description" ""
			(at 203.2 210.82 0)
			(effects
				(font
					(size 1.27 1.27)
				)
				(hide yes)
			)
		)
		(property "MPN" "CL10A226MO7JZNC"
			(at 220.98 190.5 0)
			(effects
				(font
					(size 1.27 1.27)
					(thickness 0.15)
				)
				(justify left bottom)
				(hide yes)
			)
		)
		(property "Manufacturer" "Samsung Electro-Mechanics"
			(at 223.52 190.5 0)
			(effects
				(font
					(size 1.27 1.27)
					(thickness 0.15)
				)
				(justify left bottom)
				(hide yes)
			)
		)
		(property "License" "Apache-2.0"
			(at 226.06 190.5 0)
			(effects
				(font
					(size 1.27 1.27)
					(thickness 0.15)
				)
				(justify left bottom)
				(hide yes)
			)
		)
		(property "Val" "22u"
			(at 205.74 209.5436 90)
			(effects
				(font
					(size 1.27 1.27)
					(thickness 0.15)
				)
				(justify right)
			)
		)
		(property "Voltage" "16V"
			(at 231.14 190.5 0)
			(effects
				(font
					(size 1.27 1.27)
				)
				(justify left bottom)
				(hide yes)
			)
		)
		(property "Dielectric" ""
			(at 233.68 190.5 0)
			(effects
				(font
					(size 1.27 1.27)
				)
				(justify left bottom)
				(hide yes)
			)
		)
		(property "Author" "Antmicro"
			(at 228.6 190.5 0)
			(effects
				(font
					(size 1.27 1.27)
					(thickness 0.15)
				)
				(justify left bottom)
				(hide yes)
			)
		)
		(pin "1"
		)
		(pin "2"
		)
		(instances
			(project "thunderbolt-gpu-adapter"
				(path ""
					(reference "C40")
					(unit 1)
				)
			)
		)
	)
	(symbol
		(lib_id "antmicroResistors0402:R_10k_0402")
		(at 160.02 134.62 90)
		(unit 1)
		(exclude_from_sim no)
		(in_bom yes)
		(on_board yes)
		(dnp no)
		(property "Reference" "R39"
			(at 161.29 130.81 90)
			(effects
				(font
					(size 1.27 1.27)
					(thickness 0.15)
				)
				(justify right)
			)
		)
		(property "Value" "R_10k_0402"
			(at 172.72 114.3 0)
			(effects
				(font
					(size 1.27 1.27)
					(thickness 0.15)
				)
				(justify left bottom)
				(hide yes)
			)
		)
		(property "Footprint" "antmicro-footprints:R_0402_1005Metric"
			(at 175.26 114.3 0)
			(effects
				(font
					(size 1.27 1.27)
					(thickness 0.15)
				)
				(justify left bottom)
				(hide yes)
			)
		)
		(property "Datasheet" "https://www.bourns.com/docs/product-datasheets/cr.pdf"
			(at 177.8 114.3 0)
			(effects
				(font
					(size 1.27 1.27)
					(thickness 0.15)
				)
				(justify left bottom)
				(hide yes)
			)
		)
		(property "Description" ""
			(at 160.02 134.62 0)
			(effects
				(font
					(size 1.27 1.27)
				)
				(hide yes)
			)
		)
		(property "MPN" "CR0402-FX-1002GLF"
			(at 180.34 114.3 0)
			(effects
				(font
					(size 1.27 1.27)
					(thickness 0.15)
				)
				(justify left bottom)
				(hide yes)
			)
		)
		(property "Manufacturer" "Bourns"
			(at 182.88 114.3 0)
			(effects
				(font
					(size 1.27 1.27)
					(thickness 0.15)
				)
				(justify left bottom)
				(hide yes)
			)
		)
		(property "License" "Apache-2.0"
			(at 185.42 114.3 0)
			(effects
				(font
					(size 1.27 1.27)
					(thickness 0.15)
				)
				(justify left bottom)
				(hide yes)
			)
		)
		(property "Val" "10k"
			(at 161.29 133.35 90)
			(effects
				(font
					(size 1.27 1.27)
					(thickness 0.15)
				)
				(justify right)
			)
		)
		(property "Tolerance" "1%"
			(at 170.18 114.3 0)
			(effects
				(font
					(size 1.27 1.27)
				)
				(justify left bottom)
				(hide yes)
			)
		)
		(property "Author" "Antmicro"
			(at 187.96 114.3 0)
			(effects
				(font
					(size 1.27 1.27)
					(thickness 0.15)
				)
				(justify left bottom)
				(hide yes)
			)
		)
		(pin "1"
		)
		(pin "2"
		)
		(instances
			(project "thunderbolt-gpu-adapter"
				(path ""
					(reference "R39")
					(unit 1)
				)
			)
		)
	)
	(symbol
		(lib_id "antmicroCapacitors0402:C_100n_0402")
		(at 163.83 55.88 90)
		(unit 1)
		(exclude_from_sim no)
		(in_bom yes)
		(on_board yes)
		(dnp no)
		(fields_autoplaced yes)
		(property "Reference" "C151"
			(at 166.37 52.0636 90)
			(effects
				(font
					(size 1.27 1.27)
					(thickness 0.15)
				)
				(justify right)
			)
		)
		(property "Value" "C_100n_0402"
			(at 173.99 35.56 0)
			(effects
				(font
					(size 1.27 1.27)
					(thickness 0.15)
				)
				(justify left bottom)
				(hide yes)
			)
		)
		(property "Footprint" "antmicro-footprints:C_0402_1005Metric"
			(at 176.53 35.56 0)
			(effects
				(font
					(size 1.27 1.27)
					(thickness 0.15)
				)
				(justify left bottom)
				(hide yes)
			)
		)
		(property "Datasheet" "https://www.murata.com/products/productdetail?partno=GRM155R61H104KE14%23"
			(at 179.07 35.56 0)
			(effects
				(font
					(size 1.27 1.27)
					(thickness 0.15)
				)
				(justify left bottom)
				(hide yes)
			)
		)
		(property "Description" ""
			(at 163.83 55.88 0)
			(effects
				(font
					(size 1.27 1.27)
				)
				(hide yes)
			)
		)
		(property "MPN" "GRM155R61H104KE14D"
			(at 181.61 35.56 0)
			(effects
				(font
					(size 1.27 1.27)
					(thickness 0.15)
				)
				(justify left bottom)
				(hide yes)
			)
		)
		(property "Manufacturer" "Murata"
			(at 184.15 35.56 0)
			(effects
				(font
					(size 1.27 1.27)
					(thickness 0.15)
				)
				(justify left bottom)
				(hide yes)
			)
		)
		(property "License" "Apache-2.0"
			(at 186.69 35.56 0)
			(effects
				(font
					(size 1.27 1.27)
					(thickness 0.15)
				)
				(justify left bottom)
				(hide yes)
			)
		)
		(property "Author" "Antmicro"
			(at 189.23 35.56 0)
			(effects
				(font
					(size 1.27 1.27)
					(thickness 0.15)
				)
				(justify left bottom)
				(hide yes)
			)
		)
		(property "Val" "100n"
			(at 166.37 54.6036 90)
			(effects
				(font
					(size 1.27 1.27)
					(thickness 0.15)
				)
				(justify right)
			)
		)
		(property "Voltage" "50V"
			(at 191.77 35.56 0)
			(effects
				(font
					(size 1.27 1.27)
				)
				(justify left bottom)
				(hide yes)
			)
		)
		(property "Dielectric" "X5R"
			(at 194.31 35.56 0)
			(effects
				(font
					(size 1.27 1.27)
				)
				(justify left bottom)
				(hide yes)
			)
		)
		(pin "1"
		)
		(pin "2"
		)
		(instances
			(project "thunderbolt-gpu-adapter"
				(path ""
					(reference "C151")
					(unit 1)
				)
			)
		)
	)
	(symbol
		(lib_id "antmicroCapacitorsmisc:C_10u_0805_35V")
		(at 36.83 339.09 90)
		(unit 1)
		(exclude_from_sim no)
		(in_bom yes)
		(on_board yes)
		(dnp no)
		(fields_autoplaced yes)
		(property "Reference" "C9"
			(at 39.37 335.2736 90)
			(effects
				(font
					(size 1.27 1.27)
					(thickness 0.15)
				)
				(justify right)
			)
		)
		(property "Value" "C_10u_0805_35V"
			(at 46.99 318.77 0)
			(effects
				(font
					(size 1.27 1.27)
					(thickness 0.15)
				)
				(justify left bottom)
				(hide yes)
			)
		)
		(property "Footprint" "antmicro-footprints:C_0805_2012Metric"
			(at 49.53 318.77 0)
			(effects
				(font
					(size 1.27 1.27)
					(thickness 0.15)
				)
				(justify left bottom)
				(hide yes)
			)
		)
		(property "Datasheet" "https://www.murata.com/products/productdetail?partno=GRM21BR6YA106KE43%23"
			(at 52.07 318.77 0)
			(effects
				(font
					(size 1.27 1.27)
					(thickness 0.15)
				)
				(justify left bottom)
				(hide yes)
			)
		)
		(property "Description" ""
			(at 36.83 339.09 0)
			(effects
				(font
					(size 1.27 1.27)
				)
				(hide yes)
			)
		)
		(property "MPN" "GRM21BR6YA106KE43L"
			(at 54.61 318.77 0)
			(effects
				(font
					(size 1.27 1.27)
					(thickness 0.15)
				)
				(justify left bottom)
				(hide yes)
			)
		)
		(property "Manufacturer" "Murata"
			(at 57.15 318.77 0)
			(effects
				(font
					(size 1.27 1.27)
					(thickness 0.15)
				)
				(justify left bottom)
				(hide yes)
			)
		)
		(property "License" "Apache-2.0"
			(at 59.69 318.77 0)
			(effects
				(font
					(size 1.27 1.27)
					(thickness 0.15)
				)
				(justify left bottom)
				(hide yes)
			)
		)
		(property "Val" "10u"
			(at 39.37 337.8136 90)
			(effects
				(font
					(size 1.27 1.27)
					(thickness 0.15)
				)
				(justify right)
			)
		)
		(property "Voltage" "35V"
			(at 64.77 318.77 0)
			(effects
				(font
					(size 1.27 1.27)
				)
				(justify left bottom)
				(hide yes)
			)
		)
		(property "Dielectric" ""
			(at 67.31 318.77 0)
			(effects
				(font
					(size 1.27 1.27)
				)
				(justify left bottom)
				(hide yes)
			)
		)
		(property "Author" "Antmicro"
			(at 62.23 318.77 0)
			(effects
				(font
					(size 1.27 1.27)
					(thickness 0.15)
				)
				(justify left bottom)
				(hide yes)
			)
		)
		(pin "1"
		)
		(pin "2"
		)
		(instances
			(project "thunderbolt-gpu-adapter"
				(path ""
					(reference "C9")
					(unit 1)
				)
			)
		)
	)
	(symbol
		(lib_id "antmicropower:GND")
		(at 172.72 213.36 0)
		(unit 1)
		(exclude_from_sim no)
		(in_bom yes)
		(on_board yes)
		(dnp no)
		(property "Reference" "#PWR0237"
			(at 172.72 219.71 0)
			(effects
				(font
					(size 1.27 1.27)
				)
				(hide yes)
			)
		)
		(property "Value" "GND"
			(at 166.37 215.9 0)
			(effects
				(font
					(size 1.27 1.27)
					(thickness 0.15)
				)
				(justify left bottom)
			)
		)
		(property "Footprint" ""
			(at 172.72 213.36 0)
			(effects
				(font
					(size 1.27 1.27)
					(thickness 0.15)
				)
				(justify left bottom)
				(hide yes)
			)
		)
		(property "Datasheet" ""
			(at 172.72 213.36 0)
			(effects
				(font
					(size 1.27 1.27)
					(thickness 0.15)
				)
				(justify left bottom)
				(hide yes)
			)
		)
		(property "Description" ""
			(at 172.72 213.36 0)
			(effects
				(font
					(size 1.27 1.27)
				)
				(hide yes)
			)
		)
		(property "Author" "Antmicro"
			(at 181.61 220.98 0)
			(effects
				(font
					(size 1.27 1.27)
					(thickness 0.15)
				)
				(justify left bottom)
				(hide yes)
			)
		)
		(property "License" "Apache-2.0"
			(at 181.61 223.52 0)
			(effects
				(font
					(size 1.27 1.27)
					(thickness 0.15)
				)
				(justify left bottom)
				(hide yes)
			)
		)
		(pin "1"
		)
		(instances
			(project "thunderbolt-gpu-adapter"
				(path ""
					(reference "#PWR0237")
					(unit 1)
				)
			)
		)
	)
	(symbol
		(lib_id "antmicropower:GND")
		(at 64.77 340.36 0)
		(unit 1)
		(exclude_from_sim no)
		(in_bom yes)
		(on_board yes)
		(dnp no)
		(property "Reference" "#PWR019"
			(at 64.77 346.71 0)
			(effects
				(font
					(size 1.27 1.27)
				)
				(hide yes)
			)
		)
		(property "Value" "GND"
			(at 64.77 344.17 0)
			(effects
				(font
					(size 1.27 1.27)
				)
			)
		)
		(property "Footprint" ""
			(at 64.77 340.36 0)
			(effects
				(font
					(size 1.27 1.27)
				)
				(hide yes)
			)
		)
		(property "Datasheet" ""
			(at 64.77 340.36 0)
			(effects
				(font
					(size 1.27 1.27)
				)
				(hide yes)
			)
		)
		(property "Description" ""
			(at 64.77 340.36 0)
			(effects
				(font
					(size 1.27 1.27)
				)
				(hide yes)
			)
		)
		(property "Author" "Antmicro"
			(at 73.66 347.98 0)
			(effects
				(font
					(size 1.27 1.27)
					(thickness 0.15)
				)
				(justify left bottom)
				(hide yes)
			)
		)
		(property "License" "Apache-2.0"
			(at 73.66 350.52 0)
			(effects
				(font
					(size 1.27 1.27)
					(thickness 0.15)
				)
				(justify left bottom)
				(hide yes)
			)
		)
		(pin "1"
		)
		(instances
			(project "thunderbolt-gpu-adapter"
				(path ""
					(reference "#PWR019")
					(unit 1)
				)
			)
		)
	)
	(symbol
		(lib_id "antmicropower:GND")
		(at 148.59 54.61 0)
		(unit 1)
		(exclude_from_sim no)
		(in_bom yes)
		(on_board yes)
		(dnp no)
		(property "Reference" "#PWR059"
			(at 148.59 60.96 0)
			(effects
				(font
					(size 1.27 1.27)
				)
				(hide yes)
			)
		)
		(property "Value" "GND"
			(at 148.59 58.42 0)
			(effects
				(font
					(size 1.27 1.27)
				)
			)
		)
		(property "Footprint" ""
			(at 148.59 54.61 0)
			(effects
				(font
					(size 1.27 1.27)
				)
				(hide yes)
			)
		)
		(property "Datasheet" ""
			(at 148.59 54.61 0)
			(effects
				(font
					(size 1.27 1.27)
				)
				(hide yes)
			)
		)
		(property "Description" ""
			(at 148.59 54.61 0)
			(effects
				(font
					(size 1.27 1.27)
				)
				(hide yes)
			)
		)
		(property "Author" "Antmicro"
			(at 157.48 62.23 0)
			(effects
				(font
					(size 1.27 1.27)
					(thickness 0.15)
				)
				(justify left bottom)
				(hide yes)
			)
		)
		(property "License" "Apache-2.0"
			(at 157.48 64.77 0)
			(effects
				(font
					(size 1.27 1.27)
					(thickness 0.15)
				)
				(justify left bottom)
				(hide yes)
			)
		)
		(pin "1"
		)
		(instances
			(project "thunderbolt-gpu-adapter"
				(path ""
					(reference "#PWR059")
					(unit 1)
				)
			)
		)
	)
	(symbol
		(lib_id "antmicroCapacitors0402:C_100n_0402")
		(at 162.56 228.6 0)
		(unit 1)
		(exclude_from_sim no)
		(in_bom yes)
		(on_board yes)
		(dnp no)
		(property "Reference" "C26"
			(at 169.545 227.33 0)
			(effects
				(font
					(size 1.27 1.27)
					(thickness 0.15)
				)
				(justify right)
			)
		)
		(property "Value" "C_100n_0402"
			(at 182.88 238.76 0)
			(effects
				(font
					(size 1.27 1.27)
					(thickness 0.15)
				)
				(justify left bottom)
				(hide yes)
			)
		)
		(property "Footprint" "antmicro-footprints:C_0402_1005Metric"
			(at 182.88 241.3 0)
			(effects
				(font
					(size 1.27 1.27)
					(thickness 0.15)
				)
				(justify left bottom)
				(hide yes)
			)
		)
		(property "Datasheet" "https://www.murata.com/products/productdetail?partno=GRM155R61H104KE14%23"
			(at 182.88 243.84 0)
			(effects
				(font
					(size 1.27 1.27)
					(thickness 0.15)
				)
				(justify left bottom)
				(hide yes)
			)
		)
		(property "Description" ""
			(at 162.56 228.6 0)
			(effects
				(font
					(size 1.27 1.27)
				)
				(hide yes)
			)
		)
		(property "MPN" "GRM155R61H104KE14D"
			(at 182.88 246.38 0)
			(effects
				(font
					(size 1.27 1.27)
					(thickness 0.15)
				)
				(justify left bottom)
				(hide yes)
			)
		)
		(property "Manufacturer" "Murata"
			(at 182.88 248.92 0)
			(effects
				(font
					(size 1.27 1.27)
					(thickness 0.15)
				)
				(justify left bottom)
				(hide yes)
			)
		)
		(property "License" "Apache-2.0"
			(at 182.88 251.46 0)
			(effects
				(font
					(size 1.27 1.27)
					(thickness 0.15)
				)
				(justify left bottom)
				(hide yes)
			)
		)
		(property "Val" "100n"
			(at 159.385 227.965 0)
			(effects
				(font
					(size 1.27 1.27)
					(thickness 0.15)
				)
				(justify left bottom)
			)
		)
		(property "Voltage" "50V"
			(at 182.88 256.54 0)
			(effects
				(font
					(size 1.27 1.27)
				)
				(justify left bottom)
				(hide yes)
			)
		)
		(property "Dielectric" "X5R"
			(at 182.88 259.08 0)
			(effects
				(font
					(size 1.27 1.27)
				)
				(justify left bottom)
				(hide yes)
			)
		)
		(property "Author" "Antmicro"
			(at 182.88 254 0)
			(effects
				(font
					(size 1.27 1.27)
					(thickness 0.15)
				)
				(justify left bottom)
				(hide yes)
			)
		)
		(pin "1"
		)
		(pin "2"
		)
		(instances
			(project "thunderbolt-gpu-adapter"
				(path ""
					(reference "C26")
					(unit 1)
				)
			)
		)
	)
	(symbol
		(lib_id "antmicroResistors0402:R_1k_0402")
		(at 198.12 129.54 0)
		(unit 1)
		(exclude_from_sim no)
		(in_bom yes)
		(on_board yes)
		(dnp no)
		(fields_autoplaced yes)
		(property "Reference" "R116"
			(at 200.66 133.35 0)
			(effects
				(font
					(size 1.27 1.27)
					(thickness 0.15)
				)
			)
		)
		(property "Value" "R_1k_0402"
			(at 218.44 142.24 0)
			(effects
				(font
					(size 1.27 1.27)
					(thickness 0.15)
				)
				(justify left bottom)
				(hide yes)
			)
		)
		(property "Footprint" "antmicro-footprints:R_0402_1005Metric"
			(at 218.44 144.78 0)
			(effects
				(font
					(size 1.27 1.27)
					(thickness 0.15)
				)
				(justify left bottom)
				(hide yes)
			)
		)
		(property "Datasheet" "https://www.bourns.com/docs/product-datasheets/cr.pdf"
			(at 218.44 147.32 0)
			(effects
				(font
					(size 1.27 1.27)
					(thickness 0.15)
				)
				(justify left bottom)
				(hide yes)
			)
		)
		(property "Description" ""
			(at 198.12 129.54 0)
			(effects
				(font
					(size 1.27 1.27)
				)
				(hide yes)
			)
		)
		(property "MPN" "CR0402-FX-1001GLF"
			(at 218.44 149.86 0)
			(effects
				(font
					(size 1.27 1.27)
					(thickness 0.15)
				)
				(justify left bottom)
				(hide yes)
			)
		)
		(property "Manufacturer" "Bourns"
			(at 218.44 152.4 0)
			(effects
				(font
					(size 1.27 1.27)
					(thickness 0.15)
				)
				(justify left bottom)
				(hide yes)
			)
		)
		(property "License" "Apache-2.0"
			(at 218.44 154.94 0)
			(effects
				(font
					(size 1.27 1.27)
					(thickness 0.15)
				)
				(justify left bottom)
				(hide yes)
			)
		)
		(property "Val" "1k"
			(at 200.66 135.89 0)
			(effects
				(font
					(size 1.27 1.27)
					(thickness 0.15)
				)
			)
		)
		(property "Tolerance" "1%"
			(at 218.44 139.7 0)
			(effects
				(font
					(size 1.27 1.27)
				)
				(justify left bottom)
				(hide yes)
			)
		)
		(property "Author" "Antmicro"
			(at 218.44 157.48 0)
			(effects
				(font
					(size 1.27 1.27)
					(thickness 0.15)
				)
				(justify left bottom)
				(hide yes)
			)
		)
		(pin "1"
		)
		(pin "2"
		)
		(instances
			(project "thunderbolt-gpu-adapter"
				(path ""
					(reference "R116")
					(unit 1)
				)
			)
		)
	)
	(symbol
		(lib_id "antmicropower:GND")
		(at 265.43 318.77 0)
		(unit 1)
		(exclude_from_sim no)
		(in_bom yes)
		(on_board yes)
		(dnp no)
		(property "Reference" "#PWR0213"
			(at 265.43 325.12 0)
			(effects
				(font
					(size 1.27 1.27)
				)
				(hide yes)
			)
		)
		(property "Value" "GND"
			(at 265.43 322.58 0)
			(effects
				(font
					(size 1.27 1.27)
				)
			)
		)
		(property "Footprint" ""
			(at 265.43 318.77 0)
			(effects
				(font
					(size 1.27 1.27)
				)
				(hide yes)
			)
		)
		(property "Datasheet" ""
			(at 265.43 318.77 0)
			(effects
				(font
					(size 1.27 1.27)
				)
				(hide yes)
			)
		)
		(property "Description" ""
			(at 265.43 318.77 0)
			(effects
				(font
					(size 1.27 1.27)
				)
				(hide yes)
			)
		)
		(property "Author" "Antmicro"
			(at 274.32 326.39 0)
			(effects
				(font
					(size 1.27 1.27)
					(thickness 0.15)
				)
				(justify left bottom)
				(hide yes)
			)
		)
		(property "License" "Apache-2.0"
			(at 274.32 328.93 0)
			(effects
				(font
					(size 1.27 1.27)
					(thickness 0.15)
				)
				(justify left bottom)
				(hide yes)
			)
		)
		(pin "1"
		)
		(instances
			(project "thunderbolt-gpu-adapter"
				(path ""
					(reference "#PWR0213")
					(unit 1)
				)
			)
		)
	)
	(symbol
		(lib_id "antmicroCapacitors0402:C_4u7_25V_0402")
		(at 64.77 46.99 0)
		(unit 1)
		(exclude_from_sim no)
		(in_bom yes)
		(on_board yes)
		(dnp no)
		(fields_autoplaced yes)
		(property "Reference" "C20"
			(at 64.77 45.72 0)
			(effects
				(font
					(size 1.27 1.27)
					(thickness 0.15)
				)
			)
		)
		(property "Value" "C_4u7_25V_0402"
			(at 85.09 57.15 0)
			(effects
				(font
					(size 1.27 1.27)
					(thickness 0.15)
				)
				(justify left bottom)
				(hide yes)
			)
		)
		(property "Footprint" "antmicro-footprints:C_0402_1005Metric"
			(at 85.09 59.69 0)
			(effects
				(font
					(size 1.27 1.27)
					(thickness 0.15)
				)
				(justify left bottom)
				(hide yes)
			)
		)
		(property "Datasheet" "https://www.murata.com/products/productdetail?partno=GRM155C61E475ME15%23"
			(at 85.09 62.23 0)
			(effects
				(font
					(size 1.27 1.27)
					(thickness 0.15)
				)
				(justify left bottom)
				(hide yes)
			)
		)
		(property "Description" ""
			(at 64.77 46.99 0)
			(effects
				(font
					(size 1.27 1.27)
				)
				(hide yes)
			)
		)
		(property "MPN" "GRM155C61E475ME15J"
			(at 85.09 64.77 0)
			(effects
				(font
					(size 1.27 1.27)
					(thickness 0.15)
				)
				(justify left bottom)
				(hide yes)
			)
		)
		(property "Manufacturer" "Murata"
			(at 85.09 67.31 0)
			(effects
				(font
					(size 1.27 1.27)
					(thickness 0.15)
				)
				(justify left bottom)
				(hide yes)
			)
		)
		(property "License" "Apache-2.0"
			(at 85.09 69.85 0)
			(effects
				(font
					(size 1.27 1.27)
					(thickness 0.15)
				)
				(justify left bottom)
				(hide yes)
			)
		)
		(property "Val" "4u7"
			(at 69.85 45.72 0)
			(effects
				(font
					(size 1.27 1.27)
					(thickness 0.15)
				)
			)
		)
		(property "Voltage" "25V"
			(at 68.58 46.99 0)
			(effects
				(font
					(size 1.27 1.27)
				)
				(justify left bottom)
				(hide yes)
			)
		)
		(property "Dielectric" "X5S"
			(at 85.09 77.47 0)
			(effects
				(font
					(size 1.27 1.27)
				)
				(justify left bottom)
				(hide yes)
			)
		)
		(property "Author" "Antmicro"
			(at 85.09 72.39 0)
			(effects
				(font
					(size 1.27 1.27)
					(thickness 0.15)
				)
				(justify left bottom)
				(hide yes)
			)
		)
		(pin "1"
		)
		(pin "2"
		)
		(instances
			(project "thunderbolt-gpu-adapter"
				(path ""
					(reference "C20")
					(unit 1)
				)
			)
		)
	)
	(symbol
		(lib_id "antmicropower:GND")
		(at 199.39 364.49 0)
		(unit 1)
		(exclude_from_sim no)
		(in_bom yes)
		(on_board yes)
		(dnp no)
		(fields_autoplaced yes)
		(property "Reference" "#PWR071"
			(at 199.39 370.84 0)
			(effects
				(font
					(size 1.27 1.27)
				)
				(hide yes)
			)
		)
		(property "Value" "GND"
			(at 199.39 368.3 0)
			(effects
				(font
					(size 1.27 1.27)
				)
			)
		)
		(property "Footprint" ""
			(at 199.39 364.49 0)
			(effects
				(font
					(size 1.27 1.27)
				)
				(hide yes)
			)
		)
		(property "Datasheet" ""
			(at 199.39 364.49 0)
			(effects
				(font
					(size 1.27 1.27)
				)
				(hide yes)
			)
		)
		(property "Description" ""
			(at 199.39 364.49 0)
			(effects
				(font
					(size 1.27 1.27)
				)
				(hide yes)
			)
		)
		(property "Author" "Antmicro"
			(at 208.28 372.11 0)
			(effects
				(font
					(size 1.27 1.27)
					(thickness 0.15)
				)
				(justify left bottom)
				(hide yes)
			)
		)
		(property "License" "Apache-2.0"
			(at 208.28 374.65 0)
			(effects
				(font
					(size 1.27 1.27)
					(thickness 0.15)
				)
				(justify left bottom)
				(hide yes)
			)
		)
		(pin "1"
		)
		(instances
			(project "thunderbolt-gpu-adapter"
				(path ""
					(reference "#PWR071")
					(unit 1)
				)
			)
		)
	)
	(symbol
		(lib_id "antmicroResistors0402:R_15k_0.1%_0402")
		(at 135.89 158.75 0)
		(unit 1)
		(exclude_from_sim no)
		(in_bom yes)
		(on_board yes)
		(dnp no)
		(property "Reference" "R35"
			(at 133.985 157.48 0)
			(effects
				(font
					(size 1.27 1.27)
					(thickness 0.15)
				)
			)
		)
		(property "Value" "R_15k_0.1%_0402"
			(at 156.21 171.45 0)
			(effects
				(font
					(size 1.27 1.27)
					(thickness 0.15)
				)
				(justify left bottom)
				(hide yes)
			)
		)
		(property "Footprint" "antmicro-footprints:R_0402_1005Metric"
			(at 156.21 173.99 0)
			(effects
				(font
					(size 1.27 1.27)
					(thickness 0.15)
				)
				(justify left bottom)
				(hide yes)
			)
		)
		(property "Datasheet" "https://www.mouser.com/datasheet/2/315/AOA0000C307-1149632.pdf"
			(at 156.21 176.53 0)
			(effects
				(font
					(size 1.27 1.27)
					(thickness 0.15)
				)
				(justify left bottom)
				(hide yes)
			)
		)
		(property "Description" ""
			(at 135.89 158.75 0)
			(effects
				(font
					(size 1.27 1.27)
				)
				(hide yes)
			)
		)
		(property "MPN" "ERA-2ARB153X"
			(at 156.21 179.07 0)
			(effects
				(font
					(size 1.27 1.27)
					(thickness 0.15)
				)
				(justify left bottom)
				(hide yes)
			)
		)
		(property "Manufacturer" "Panasonic"
			(at 156.21 181.61 0)
			(effects
				(font
					(size 1.27 1.27)
					(thickness 0.15)
				)
				(justify left bottom)
				(hide yes)
			)
		)
		(property "License" "Apache-2.0"
			(at 156.21 184.15 0)
			(effects
				(font
					(size 1.27 1.27)
					(thickness 0.15)
				)
				(justify left bottom)
				(hide yes)
			)
		)
		(property "Val" "15k"
			(at 142.24 157.48 0)
			(effects
				(font
					(size 1.27 1.27)
					(thickness 0.15)
				)
			)
		)
		(property "Tolerance" "0.1%"
			(at 138.43 162.56 0)
			(effects
				(font
					(size 1.27 1.27)
				)
				(hide yes)
			)
		)
		(property "Author" "Antmicro"
			(at 156.21 186.69 0)
			(effects
				(font
					(size 1.27 1.27)
					(thickness 0.15)
				)
				(justify left bottom)
				(hide yes)
			)
		)
		(pin "1"
		)
		(pin "2"
		)
		(instances
			(project "thunderbolt-gpu-adapter"
				(path ""
					(reference "R35")
					(unit 1)
				)
			)
		)
	)
	(symbol
		(lib_id "antmicroDiodesZenerSingle:MM3Z3V3C")
		(at 81.28 351.79 270)
		(unit 1)
		(exclude_from_sim no)
		(in_bom yes)
		(on_board yes)
		(dnp no)
		(fields_autoplaced yes)
		(property "Reference" "D1"
			(at 83.82 353.06 90)
			(effects
				(font
					(size 1.27 1.27)
					(thickness 0.15)
				)
				(justify left)
			)
		)
		(property "Value" "MM3Z3V3C"
			(at 78.74 351.155 0)
			(effects
				(font
					(size 1.27 1.27)
					(thickness 0.15)
				)
				(justify left)
				(hide yes)
			)
		)
		(property "Footprint" "antmicro-footprints:D_SOD-323F"
			(at 71.12 374.65 0)
			(effects
				(font
					(size 1.27 1.27)
					(thickness 0.15)
				)
				(justify left bottom)
				(hide yes)
			)
		)
		(property "Datasheet" "https://www.onsemi.com/download/data-sheet/pdf/mm3z9v1c-d.pdf"
			(at 68.58 374.65 0)
			(effects
				(font
					(size 1.27 1.27)
					(thickness 0.15)
				)
				(justify left bottom)
				(hide yes)
			)
		)
		(property "Description" ""
			(at 81.28 351.79 0)
			(effects
				(font
					(size 1.27 1.27)
				)
				(hide yes)
			)
		)
		(property "MPN" "MM3Z3V3C"
			(at 83.82 355.6 90)
			(effects
				(font
					(size 1.27 1.27)
					(thickness 0.15)
				)
				(justify left)
			)
		)
		(property "Manufacturer" "ON Semiconductor"
			(at 63.5 374.65 0)
			(effects
				(font
					(size 1.27 1.27)
					(thickness 0.15)
				)
				(justify left bottom)
				(hide yes)
			)
		)
		(property "License" "Apache-2.0"
			(at 58.42 374.65 0)
			(effects
				(font
					(size 1.27 1.27)
					(thickness 0.15)
				)
				(justify left bottom)
				(hide yes)
			)
		)
		(property "Author" "Antmicro"
			(at 60.96 374.65 0)
			(effects
				(font
					(size 1.27 1.27)
					(thickness 0.15)
				)
				(justify left bottom)
				(hide yes)
			)
		)
		(pin "2"
		)
		(pin "1"
		)
		(instances
			(project "thunderbolt-gpu-adapter"
				(path ""
					(reference "D1")
					(unit 1)
				)
			)
		)
	)
	(symbol
		(lib_id "antmicroCapacitorspol:C_Pol_330u_6.3V_KEMET-T520-B")
		(at 220.98 353.06 270)
		(unit 1)
		(exclude_from_sim no)
		(in_bom yes)
		(on_board yes)
		(dnp no)
		(fields_autoplaced yes)
		(property "Reference" "C141"
			(at 218.44 353.7966 90)
			(effects
				(font
					(size 1.27 1.27)
					(thickness 0.15)
				)
				(justify right)
			)
		)
		(property "Value" "C_Pol_330u_6.3V_KEMET-T520-B"
			(at 218.44 367.03 0)
			(effects
				(font
					(size 1.27 1.27)
					(thickness 0.15)
				)
				(justify left bottom)
				(hide yes)
			)
		)
		(property "Footprint" "antmicro-footprints:C_Pol_EIA-B"
			(at 213.36 367.03 0)
			(effects
				(font
					(size 1.27 1.27)
					(thickness 0.15)
				)
				(justify left bottom)
				(hide yes)
			)
		)
		(property "Datasheet" "https://www.kemet.com/en/us/capacitors/product/T520B337M006ATE040.html"
			(at 210.82 367.03 0)
			(effects
				(font
					(size 1.27 1.27)
					(thickness 0.15)
				)
				(justify left bottom)
				(hide yes)
			)
		)
		(property "Description" ""
			(at 220.98 353.06 0)
			(effects
				(font
					(size 1.27 1.27)
				)
				(hide yes)
			)
		)
		(property "Val" "330u"
			(at 218.44 356.3366 90)
			(effects
				(font
					(size 1.27 1.27)
					(thickness 0.15)
				)
				(justify right)
			)
		)
		(property "MPN" "T520B337M006ATE040"
			(at 208.28 367.03 0)
			(effects
				(font
					(size 1.27 1.27)
					(thickness 0.15)
				)
				(justify left bottom)
				(hide yes)
			)
		)
		(property "Manufacturer" "KEMET"
			(at 205.74 367.03 0)
			(effects
				(font
					(size 1.27 1.27)
					(thickness 0.15)
				)
				(justify left bottom)
				(hide yes)
			)
		)
		(property "License" "Apache-2.0"
			(at 203.2 367.03 0)
			(effects
				(font
					(size 1.27 1.27)
					(thickness 0.15)
				)
				(justify left bottom)
				(hide yes)
			)
		)
		(property "Author" "Antmicro"
			(at 200.66 367.03 0)
			(effects
				(font
					(size 1.27 1.27)
					(thickness 0.15)
				)
				(justify left bottom)
				(hide yes)
			)
		)
		(property "Voltage" "6.3V"
			(at 198.12 367.03 0)
			(effects
				(font
					(size 1.27 1.27)
				)
				(justify left bottom)
				(hide yes)
			)
		)
		(property "Dielectric" "template_dielectric"
			(at 195.58 367.03 0)
			(effects
				(font
					(size 1.27 1.27)
				)
				(justify left bottom)
				(hide yes)
			)
		)
		(pin "1"
		)
		(pin "2"
		)
		(instances
			(project "thunderbolt-gpu-adapter"
				(path ""
					(reference "C141")
					(unit 1)
				)
			)
		)
	)
	(symbol
		(lib_id "antmicroResistors0402:R_100k_0402")
		(at 217.17 135.89 90)
		(unit 1)
		(exclude_from_sim no)
		(in_bom yes)
		(on_board yes)
		(dnp no)
		(property "Reference" "R121"
			(at 219.075 132.08 90)
			(effects
				(font
					(size 1.27 1.27)
					(thickness 0.15)
				)
				(justify right)
			)
		)
		(property "Value" "R_100k_0402"
			(at 229.87 115.57 0)
			(effects
				(font
					(size 1.27 1.27)
					(thickness 0.15)
				)
				(justify left bottom)
				(hide yes)
			)
		)
		(property "Footprint" "antmicro-footprints:R_0402_1005Metric"
			(at 232.41 115.57 0)
			(effects
				(font
					(size 1.27 1.27)
					(thickness 0.15)
				)
				(justify left bottom)
				(hide yes)
			)
		)
		(property "Datasheet" "https://www.bourns.com/docs/product-datasheets/cr.pdf"
			(at 234.95 115.57 0)
			(effects
				(font
					(size 1.27 1.27)
					(thickness 0.15)
				)
				(justify left bottom)
				(hide yes)
			)
		)
		(property "Description" ""
			(at 217.17 135.89 0)
			(effects
				(font
					(size 1.27 1.27)
				)
				(hide yes)
			)
		)
		(property "MPN" "CR0402-FX-1003GLF"
			(at 237.49 115.57 0)
			(effects
				(font
					(size 1.27 1.27)
					(thickness 0.15)
				)
				(justify left bottom)
				(hide yes)
			)
		)
		(property "Manufacturer" "Bourns"
			(at 240.03 115.57 0)
			(effects
				(font
					(size 1.27 1.27)
					(thickness 0.15)
				)
				(justify left bottom)
				(hide yes)
			)
		)
		(property "License" "Apache-2.0"
			(at 242.57 115.57 0)
			(effects
				(font
					(size 1.27 1.27)
					(thickness 0.15)
				)
				(justify left bottom)
				(hide yes)
			)
		)
		(property "Author" "Antmicro"
			(at 245.11 115.57 0)
			(effects
				(font
					(size 1.27 1.27)
					(thickness 0.15)
				)
				(justify left bottom)
				(hide yes)
			)
		)
		(property "Val" "100k"
			(at 219.075 134.62 90)
			(effects
				(font
					(size 1.27 1.27)
					(thickness 0.15)
				)
				(justify right)
			)
		)
		(property "Tolerance" "1%"
			(at 227.33 115.57 0)
			(effects
				(font
					(size 1.27 1.27)
				)
				(justify left bottom)
				(hide yes)
			)
		)
		(pin "1"
		)
		(pin "2"
		)
		(instances
			(project "thunderbolt-gpu-adapter"
				(path ""
					(reference "R121")
					(unit 1)
				)
			)
		)
	)
	(symbol
		(lib_id "antmicroTransistorsBipolarSingle:BC817-25W")
		(at 241.3 80.01 0)
		(unit 1)
		(exclude_from_sim no)
		(in_bom yes)
		(on_board yes)
		(dnp no)
		(fields_autoplaced yes)
		(property "Reference" "Q8"
			(at 250.19 78.74 0)
			(effects
				(font
					(size 1.27 1.27)
					(thickness 0.15)
				)
				(justify left)
			)
		)
		(property "Value" "BC817-25W"
			(at 264.16 82.55 0)
			(effects
				(font
					(size 1.27 1.27)
					(thickness 0.15)
				)
				(justify left bottom)
				(hide yes)
			)
		)
		(property "Footprint" "antmicro-footprints:SOT-323"
			(at 264.16 85.09 0)
			(effects
				(font
					(size 1.27 1.27)
					(thickness 0.15)
				)
				(justify left bottom)
				(hide yes)
			)
		)
		(property "Datasheet" "https://assets.nexperia.com/documents/data-sheet/BC817W_SER.pdf"
			(at 264.16 87.63 0)
			(effects
				(font
					(size 1.27 1.27)
					(thickness 0.15)
				)
				(justify left bottom)
				(hide yes)
			)
		)
		(property "Description" ""
			(at 241.3 80.01 0)
			(effects
				(font
					(size 1.27 1.27)
				)
				(hide yes)
			)
		)
		(property "MPN" "BC817-25W,115"
			(at 250.19 81.28 0)
			(effects
				(font
					(size 1.27 1.27)
					(thickness 0.15)
				)
				(justify left)
			)
		)
		(property "Manufacturer" "Nexperia"
			(at 264.16 92.71 0)
			(effects
				(font
					(size 1.27 1.27)
					(thickness 0.15)
				)
				(justify left bottom)
				(hide yes)
			)
		)
		(property "Author" "Antmicro"
			(at 264.16 95.25 0)
			(effects
				(font
					(size 1.27 1.27)
					(thickness 0.15)
				)
				(justify left bottom)
				(hide yes)
			)
		)
		(property "License" "Apache-2.0"
			(at 264.16 97.79 0)
			(effects
				(font
					(size 1.27 1.27)
					(thickness 0.15)
				)
				(justify left bottom)
				(hide yes)
			)
		)
		(pin "1"
		)
		(pin "2"
		)
		(pin "3"
		)
		(instances
			(project "thunderbolt-gpu-adapter"
				(path ""
					(reference "Q8")
					(unit 1)
				)
			)
		)
	)
	(symbol
		(lib_id "antmicroFixedInductors:L_2u2_9.7A_Coilcraft-XAL5030")
		(at 134.62 346.71 0)
		(unit 1)
		(exclude_from_sim no)
		(in_bom yes)
		(on_board yes)
		(dnp no)
		(fields_autoplaced yes)
		(property "Reference" "L2"
			(at 137.16 341.63 0)
			(effects
				(font
					(size 1.27 1.27)
					(thickness 0.15)
				)
			)
		)
		(property "Value" "L_2u2_9.7A_Coilcraft-XAL5030"
			(at 148.59 349.25 0)
			(effects
				(font
					(size 1.27 1.27)
					(thickness 0.15)
				)
				(justify left bottom)
				(hide yes)
			)
		)
		(property "Footprint" "antmicro-footprints:L_Coilcraft-XAL5030"
			(at 148.59 354.33 0)
			(effects
				(font
					(size 1.27 1.27)
					(thickness 0.15)
				)
				(justify left bottom)
				(hide yes)
			)
		)
		(property "Datasheet" "https://www.coilcraft.com/getmedia/49bc46c8-4b2c-45b9-9b6c-2eaa235ea698/xal50xx.pdf"
			(at 148.59 356.87 0)
			(effects
				(font
					(size 1.27 1.27)
					(thickness 0.15)
				)
				(justify left bottom)
				(hide yes)
			)
		)
		(property "Description" ""
			(at 134.62 346.71 0)
			(effects
				(font
					(size 1.27 1.27)
				)
				(hide yes)
			)
		)
		(property "Val" "2u2/9.7A"
			(at 137.16 344.17 0)
			(effects
				(font
					(size 1.27 1.27)
					(thickness 0.15)
				)
			)
		)
		(property "Manufacturer" "Coilcraft"
			(at 148.59 359.41 0)
			(effects
				(font
					(size 1.27 1.27)
					(thickness 0.15)
				)
				(justify left bottom)
				(hide yes)
			)
		)
		(property "MPN" "XAL5030-222MEC"
			(at 148.59 361.95 0)
			(effects
				(font
					(size 1.27 1.27)
					(thickness 0.15)
				)
				(justify left bottom)
				(hide yes)
			)
		)
		(property "ISat" "9.2 A"
			(at 148.59 363.22 0)
			(effects
				(font
					(size 1.27 1.27)
				)
				(justify left)
				(hide yes)
			)
		)
		(property "IMax" "9.7 A"
			(at 148.59 367.03 0)
			(effects
				(font
					(size 1.27 1.27)
					(thickness 0.15)
				)
				(justify left bottom)
				(hide yes)
			)
		)
		(property "Size" "5.28x5.48"
			(at 148.59 369.57 0)
			(effects
				(font
					(size 1.27 1.27)
					(thickness 0.15)
				)
				(justify left bottom)
				(hide yes)
			)
		)
		(property "Author" "Antmicro"
			(at 148.59 372.11 0)
			(effects
				(font
					(size 1.27 1.27)
					(thickness 0.15)
				)
				(justify left bottom)
				(hide yes)
			)
		)
		(property "License" "Apache-2.0"
			(at 148.59 374.65 0)
			(effects
				(font
					(size 1.27 1.27)
					(thickness 0.15)
				)
				(justify left bottom)
				(hide yes)
			)
		)
		(pin "1"
		)
		(pin "2"
		)
		(instances
			(project "thunderbolt-gpu-adapter"
				(path ""
					(reference "L2")
					(unit 1)
				)
			)
		)
	)
	(symbol
		(lib_id "antmicropower:GND")
		(at 133.35 173.99 0)
		(unit 1)
		(exclude_from_sim no)
		(in_bom yes)
		(on_board yes)
		(dnp no)
		(property "Reference" "#PWR043"
			(at 133.35 180.34 0)
			(effects
				(font
					(size 1.27 1.27)
				)
				(hide yes)
			)
		)
		(property "Value" "GND"
			(at 133.35 177.8 0)
			(effects
				(font
					(size 1.27 1.27)
				)
			)
		)
		(property "Footprint" ""
			(at 133.35 173.99 0)
			(effects
				(font
					(size 1.27 1.27)
				)
				(hide yes)
			)
		)
		(property "Datasheet" ""
			(at 133.35 173.99 0)
			(effects
				(font
					(size 1.27 1.27)
				)
				(hide yes)
			)
		)
		(property "Description" ""
			(at 133.35 173.99 0)
			(effects
				(font
					(size 1.27 1.27)
				)
				(hide yes)
			)
		)
		(property "Author" "Antmicro"
			(at 142.24 181.61 0)
			(effects
				(font
					(size 1.27 1.27)
					(thickness 0.15)
				)
				(justify left bottom)
				(hide yes)
			)
		)
		(property "License" "Apache-2.0"
			(at 142.24 184.15 0)
			(effects
				(font
					(size 1.27 1.27)
					(thickness 0.15)
				)
				(justify left bottom)
				(hide yes)
			)
		)
		(pin "1"
		)
		(instances
			(project "thunderbolt-gpu-adapter"
				(path ""
					(reference "#PWR043")
					(unit 1)
				)
			)
		)
	)
	(symbol
		(lib_id "antmicroCapacitorsmisc:C_10u_0805_35V")
		(at 76.2 204.47 270)
		(mirror x)
		(unit 1)
		(exclude_from_sim no)
		(in_bom yes)
		(on_board yes)
		(dnp no)
		(fields_autoplaced yes)
		(property "Reference" "C12"
			(at 78.74 200.6536 90)
			(effects
				(font
					(size 1.27 1.27)
					(thickness 0.15)
				)
				(justify left)
			)
		)
		(property "Value" "C_10u_0805_35V"
			(at 66.04 184.15 0)
			(effects
				(font
					(size 1.27 1.27)
					(thickness 0.15)
				)
				(justify left bottom)
				(hide yes)
			)
		)
		(property "Footprint" "antmicro-footprints:C_0805_2012Metric"
			(at 63.5 184.15 0)
			(effects
				(font
					(size 1.27 1.27)
					(thickness 0.15)
				)
				(justify left bottom)
				(hide yes)
			)
		)
		(property "Datasheet" "https://www.murata.com/products/productdetail?partno=GRM21BR6YA106KE43%23"
			(at 60.96 184.15 0)
			(effects
				(font
					(size 1.27 1.27)
					(thickness 0.15)
				)
				(justify left bottom)
				(hide yes)
			)
		)
		(property "Description" ""
			(at 76.2 204.47 0)
			(effects
				(font
					(size 1.27 1.27)
				)
				(hide yes)
			)
		)
		(property "MPN" "GRM21BR6YA106KE43L"
			(at 58.42 184.15 0)
			(effects
				(font
					(size 1.27 1.27)
					(thickness 0.15)
				)
				(justify left bottom)
				(hide yes)
			)
		)
		(property "Manufacturer" "Murata"
			(at 55.88 184.15 0)
			(effects
				(font
					(size 1.27 1.27)
					(thickness 0.15)
				)
				(justify left bottom)
				(hide yes)
			)
		)
		(property "License" "Apache-2.0"
			(at 53.34 184.15 0)
			(effects
				(font
					(size 1.27 1.27)
					(thickness 0.15)
				)
				(justify left bottom)
				(hide yes)
			)
		)
		(property "Val" "10u"
			(at 78.74 203.1936 90)
			(effects
				(font
					(size 1.27 1.27)
					(thickness 0.15)
				)
				(justify left)
			)
		)
		(property "Voltage" "35V"
			(at 48.26 184.15 0)
			(effects
				(font
					(size 1.27 1.27)
				)
				(justify left bottom)
				(hide yes)
			)
		)
		(property "Dielectric" ""
			(at 45.72 184.15 0)
			(effects
				(font
					(size 1.27 1.27)
				)
				(justify left bottom)
				(hide yes)
			)
		)
		(property "Author" "Antmicro"
			(at 50.8 184.15 0)
			(effects
				(font
					(size 1.27 1.27)
					(thickness 0.15)
				)
				(justify left bottom)
				(hide yes)
			)
		)
		(pin "1"
		)
		(pin "2"
		)
		(instances
			(project "thunderbolt-gpu-adapter"
				(path ""
					(reference "C12")
					(unit 1)
				)
			)
		)
	)
	(symbol
		(lib_id "antmicroResistors0402:R_100k_0402")
		(at 250.19 325.12 90)
		(unit 1)
		(exclude_from_sim no)
		(in_bom yes)
		(on_board yes)
		(dnp no)
		(fields_autoplaced yes)
		(property "Reference" "R96"
			(at 252.73 321.31 90)
			(effects
				(font
					(size 1.27 1.27)
					(thickness 0.15)
				)
				(justify right)
			)
		)
		(property "Value" "R_100k_0402"
			(at 262.89 304.8 0)
			(effects
				(font
					(size 1.27 1.27)
					(thickness 0.15)
				)
				(justify left bottom)
				(hide yes)
			)
		)
		(property "Footprint" "antmicro-footprints:R_0402_1005Metric"
			(at 265.43 304.8 0)
			(effects
				(font
					(size 1.27 1.27)
					(thickness 0.15)
				)
				(justify left bottom)
				(hide yes)
			)
		)
		(property "Datasheet" "https://www.bourns.com/docs/product-datasheets/cr.pdf"
			(at 267.97 304.8 0)
			(effects
				(font
					(size 1.27 1.27)
					(thickness 0.15)
				)
				(justify left bottom)
				(hide yes)
			)
		)
		(property "Description" ""
			(at 250.19 325.12 0)
			(effects
				(font
					(size 1.27 1.27)
				)
				(hide yes)
			)
		)
		(property "MPN" "CR0402-FX-1003GLF"
			(at 270.51 304.8 0)
			(effects
				(font
					(size 1.27 1.27)
					(thickness 0.15)
				)
				(justify left bottom)
				(hide yes)
			)
		)
		(property "Manufacturer" "Bourns"
			(at 273.05 304.8 0)
			(effects
				(font
					(size 1.27 1.27)
					(thickness 0.15)
				)
				(justify left bottom)
				(hide yes)
			)
		)
		(property "License" "Apache-2.0"
			(at 275.59 304.8 0)
			(effects
				(font
					(size 1.27 1.27)
					(thickness 0.15)
				)
				(justify left bottom)
				(hide yes)
			)
		)
		(property "Author" "Antmicro"
			(at 278.13 304.8 0)
			(effects
				(font
					(size 1.27 1.27)
					(thickness 0.15)
				)
				(justify left bottom)
				(hide yes)
			)
		)
		(property "Val" "100k"
			(at 252.73 323.85 90)
			(effects
				(font
					(size 1.27 1.27)
					(thickness 0.15)
				)
				(justify right)
			)
		)
		(property "Tolerance" "1%"
			(at 260.35 304.8 0)
			(effects
				(font
					(size 1.27 1.27)
				)
				(justify left bottom)
				(hide yes)
			)
		)
		(pin "1"
		)
		(pin "2"
		)
		(instances
			(project "thunderbolt-gpu-adapter"
				(path ""
					(reference "R96")
					(unit 1)
				)
			)
		)
	)
	(symbol
		(lib_id "antmicroCapacitors0603:C_10u_0603")
		(at 204.47 119.38 90)
		(unit 1)
		(exclude_from_sim no)
		(in_bom yes)
		(on_board yes)
		(dnp yes)
		(property "Reference" "C132"
			(at 206.375 115.57 90)
			(effects
				(font
					(size 1.27 1.27)
					(thickness 0.15)
				)
				(justify right)
			)
		)
		(property "Value" "C_10u_0603"
			(at 214.63 99.06 0)
			(effects
				(font
					(size 1.27 1.27)
					(thickness 0.15)
				)
				(justify left bottom)
				(hide yes)
			)
		)
		(property "Footprint" "antmicro-footprints:C_0603_1608Metric"
			(at 217.17 99.06 0)
			(effects
				(font
					(size 1.27 1.27)
					(thickness 0.15)
				)
				(justify left bottom)
				(hide yes)
			)
		)
		(property "Datasheet" "https://www.murata.com/products/productdetail?partno=GRM188R61A106KE69%23"
			(at 219.71 99.06 0)
			(effects
				(font
					(size 1.27 1.27)
					(thickness 0.15)
				)
				(justify left bottom)
				(hide yes)
			)
		)
		(property "Description" ""
			(at 204.47 119.38 0)
			(effects
				(font
					(size 1.27 1.27)
				)
				(hide yes)
			)
		)
		(property "MPN" "GRM188R61A106KE69D"
			(at 222.25 99.06 0)
			(effects
				(font
					(size 1.27 1.27)
					(thickness 0.15)
				)
				(justify left bottom)
				(hide yes)
			)
		)
		(property "Manufacturer" "Murata"
			(at 224.79 99.06 0)
			(effects
				(font
					(size 1.27 1.27)
					(thickness 0.15)
				)
				(justify left bottom)
				(hide yes)
			)
		)
		(property "License" "Apache-2.0"
			(at 227.33 99.06 0)
			(effects
				(font
					(size 1.27 1.27)
					(thickness 0.15)
				)
				(justify left bottom)
				(hide yes)
			)
		)
		(property "Author" "Antmicro"
			(at 229.87 99.06 0)
			(effects
				(font
					(size 1.27 1.27)
					(thickness 0.15)
				)
				(justify left bottom)
				(hide yes)
			)
		)
		(property "Val" "10u"
			(at 206.375 117.475 90)
			(effects
				(font
					(size 1.27 1.27)
					(thickness 0.15)
				)
				(justify right)
			)
		)
		(property "Voltage" ""
			(at 232.41 99.06 0)
			(effects
				(font
					(size 1.27 1.27)
				)
				(justify left bottom)
				(hide yes)
			)
		)
		(property "Dielectric" "template_dielectric"
			(at 234.95 99.06 0)
			(effects
				(font
					(size 1.27 1.27)
				)
				(justify left bottom)
				(hide yes)
			)
		)
		(pin "1"
		)
		(pin "2"
		)
		(instances
			(project "thunderbolt-gpu-adapter"
				(path ""
					(reference "C132")
					(unit 1)
				)
			)
		)
	)
	(symbol
		(lib_id "antmicroCapacitorspol:C_Pol_330u_6.3V_KEMET-T520-B")
		(at 229.87 353.06 270)
		(unit 1)
		(exclude_from_sim no)
		(in_bom yes)
		(on_board yes)
		(dnp no)
		(fields_autoplaced yes)
		(property "Reference" "C142"
			(at 232.41 353.7966 90)
			(effects
				(font
					(size 1.27 1.27)
					(thickness 0.15)
				)
				(justify left)
			)
		)
		(property "Value" "C_Pol_330u_6.3V_KEMET-T520-B"
			(at 227.33 367.03 0)
			(effects
				(font
					(size 1.27 1.27)
					(thickness 0.15)
				)
				(justify left bottom)
				(hide yes)
			)
		)
		(property "Footprint" "antmicro-footprints:C_Pol_EIA-B"
			(at 222.25 367.03 0)
			(effects
				(font
					(size 1.27 1.27)
					(thickness 0.15)
				)
				(justify left bottom)
				(hide yes)
			)
		)
		(property "Datasheet" "https://www.kemet.com/en/us/capacitors/product/T520B337M006ATE040.html"
			(at 219.71 367.03 0)
			(effects
				(font
					(size 1.27 1.27)
					(thickness 0.15)
				)
				(justify left bottom)
				(hide yes)
			)
		)
		(property "Description" ""
			(at 229.87 353.06 0)
			(effects
				(font
					(size 1.27 1.27)
				)
				(hide yes)
			)
		)
		(property "Val" "330u"
			(at 232.41 356.3366 90)
			(effects
				(font
					(size 1.27 1.27)
					(thickness 0.15)
				)
				(justify left)
			)
		)
		(property "MPN" "T520B337M006ATE040"
			(at 217.17 367.03 0)
			(effects
				(font
					(size 1.27 1.27)
					(thickness 0.15)
				)
				(justify left bottom)
				(hide yes)
			)
		)
		(property "Manufacturer" "KEMET"
			(at 214.63 367.03 0)
			(effects
				(font
					(size 1.27 1.27)
					(thickness 0.15)
				)
				(justify left bottom)
				(hide yes)
			)
		)
		(property "License" "Apache-2.0"
			(at 212.09 367.03 0)
			(effects
				(font
					(size 1.27 1.27)
					(thickness 0.15)
				)
				(justify left bottom)
				(hide yes)
			)
		)
		(property "Author" "Antmicro"
			(at 209.55 367.03 0)
			(effects
				(font
					(size 1.27 1.27)
					(thickness 0.15)
				)
				(justify left bottom)
				(hide yes)
			)
		)
		(property "Voltage" "6.3V"
			(at 207.01 367.03 0)
			(effects
				(font
					(size 1.27 1.27)
				)
				(justify left bottom)
				(hide yes)
			)
		)
		(property "Dielectric" "template_dielectric"
			(at 204.47 367.03 0)
			(effects
				(font
					(size 1.27 1.27)
				)
				(justify left bottom)
				(hide yes)
			)
		)
		(pin "1"
		)
		(pin "2"
		)
		(instances
			(project "thunderbolt-gpu-adapter"
				(path ""
					(reference "C142")
					(unit 1)
				)
			)
		)
	)
	(symbol
		(lib_id "antmicroTransistorsFETsMOSFETsSingle:SI7613DN-T1-GE3")
		(at 251.46 270.51 90)
		(unit 1)
		(exclude_from_sim no)
		(in_bom yes)
		(on_board yes)
		(dnp no)
		(fields_autoplaced yes)
		(property "Reference" "Q5"
			(at 248.92 256.54 90)
			(effects
				(font
					(size 1.524 1.524)
				)
			)
		)
		(property "Value" "SI7613DN-T1-GE3"
			(at 248.92 255.27 0)
			(effects
				(font
					(size 1.27 1.27)
					(thickness 0.15)
				)
				(justify left bottom)
				(hide yes)
			)
		)
		(property "Footprint" "antmicro-footprints:Vishay_PowerPAK_1212-8_Single"
			(at 250.19 255.27 0)
			(effects
				(font
					(size 1.27 1.27)
					(thickness 0.15)
				)
				(justify left bottom)
				(hide yes)
			)
		)
		(property "Datasheet" "https://www.vishay.com/docs/64809/si7613dn.pdf"
			(at 252.73 255.27 0)
			(effects
				(font
					(size 1.27 1.27)
					(thickness 0.15)
				)
				(justify left bottom)
				(hide yes)
			)
		)
		(property "Description" ""
			(at 251.46 270.51 0)
			(effects
				(font
					(size 1.27 1.27)
				)
				(hide yes)
			)
		)
		(property "MPN" "SI7613DN-T1-GE3"
			(at 248.92 259.08 90)
			(effects
				(font
					(size 1.27 1.27)
					(thickness 0.15)
				)
			)
		)
		(property "Manufacturer" "Vishay"
			(at 259.08 255.27 0)
			(effects
				(font
					(size 1.27 1.27)
					(thickness 0.15)
				)
				(justify left bottom)
				(hide yes)
			)
		)
		(property "Author" "Antmicro"
			(at 261.62 255.27 0)
			(effects
				(font
					(size 1.27 1.27)
					(thickness 0.15)
				)
				(justify left bottom)
				(hide yes)
			)
		)
		(property "License" "Apache-2.0"
			(at 264.16 255.27 0)
			(effects
				(font
					(size 1.27 1.27)
					(thickness 0.15)
				)
				(justify left bottom)
				(hide yes)
			)
		)
		(pin "1"
		)
		(pin "2"
		)
		(pin "3"
		)
		(pin "4"
		)
		(pin "5"
		)
		(instances
			(project "thunderbolt-gpu-adapter"
				(path ""
					(reference "Q5")
					(unit 1)
				)
			)
		)
	)
	(symbol
		(lib_id "antmicroResistors0402:R_0R_0402")
		(at 176.53 205.74 0)
		(unit 1)
		(exclude_from_sim no)
		(in_bom yes)
		(on_board yes)
		(dnp no)
		(property "Reference" "R26"
			(at 179.07 208.28 0)
			(effects
				(font
					(size 1.27 1.27)
					(thickness 0.15)
				)
			)
		)
		(property "Value" "R_0R_0402"
			(at 196.85 218.44 0)
			(effects
				(font
					(size 1.27 1.27)
					(thickness 0.15)
				)
				(justify left bottom)
				(hide yes)
			)
		)
		(property "Footprint" "antmicro-footprints:R_0402_1005Metric"
			(at 196.85 220.98 0)
			(effects
				(font
					(size 1.27 1.27)
					(thickness 0.15)
				)
				(justify left bottom)
				(hide yes)
			)
		)
		(property "Datasheet" "https://industrial.panasonic.com/cdbs/www-data/pdf/RDA0000/AOA0000C301.pdf"
			(at 196.85 223.52 0)
			(effects
				(font
					(size 1.27 1.27)
					(thickness 0.15)
				)
				(justify left bottom)
				(hide yes)
			)
		)
		(property "Description" ""
			(at 176.53 205.74 0)
			(effects
				(font
					(size 1.27 1.27)
				)
				(hide yes)
			)
		)
		(property "MPN" "ERJ2GE0R00X"
			(at 196.85 226.06 0)
			(effects
				(font
					(size 1.27 1.27)
					(thickness 0.15)
				)
				(justify left bottom)
				(hide yes)
			)
		)
		(property "Manufacturer" "Panasonic"
			(at 196.85 228.6 0)
			(effects
				(font
					(size 1.27 1.27)
					(thickness 0.15)
				)
				(justify left bottom)
				(hide yes)
			)
		)
		(property "License" "Apache-2.0"
			(at 196.85 231.14 0)
			(effects
				(font
					(size 1.27 1.27)
					(thickness 0.15)
				)
				(justify left bottom)
				(hide yes)
			)
		)
		(property "Val" "0R"
			(at 177.8 206.375 0)
			(effects
				(font
					(size 1.27 1.27)
					(thickness 0.15)
				)
				(justify left bottom)
			)
		)
		(property "Tolerance" "~"
			(at 196.85 215.9 0)
			(effects
				(font
					(size 1.27 1.27)
				)
				(justify left bottom)
				(hide yes)
			)
		)
		(property "Current" "1A"
			(at 196.85 236.22 0)
			(effects
				(font
					(size 1.27 1.27)
					(thickness 0.15)
				)
				(justify left bottom)
				(hide yes)
			)
		)
		(property "Author" "Antmicro"
			(at 196.85 233.68 0)
			(effects
				(font
					(size 1.27 1.27)
					(thickness 0.15)
				)
				(justify left bottom)
				(hide yes)
			)
		)
		(pin "1"
		)
		(pin "2"
		)
		(instances
			(project "thunderbolt-gpu-adapter"
				(path ""
					(reference "R26")
					(unit 1)
				)
			)
		)
	)
	(symbol
		(lib_id "antmicropower:GND")
		(at 220.98 364.49 0)
		(unit 1)
		(exclude_from_sim no)
		(in_bom yes)
		(on_board yes)
		(dnp no)
		(fields_autoplaced yes)
		(property "Reference" "#PWR0216"
			(at 220.98 370.84 0)
			(effects
				(font
					(size 1.27 1.27)
				)
				(hide yes)
			)
		)
		(property "Value" "GND"
			(at 220.98 368.3 0)
			(effects
				(font
					(size 1.27 1.27)
				)
			)
		)
		(property "Footprint" ""
			(at 220.98 364.49 0)
			(effects
				(font
					(size 1.27 1.27)
				)
				(hide yes)
			)
		)
		(property "Datasheet" ""
			(at 220.98 364.49 0)
			(effects
				(font
					(size 1.27 1.27)
				)
				(hide yes)
			)
		)
		(property "Description" ""
			(at 220.98 364.49 0)
			(effects
				(font
					(size 1.27 1.27)
				)
				(hide yes)
			)
		)
		(property "Author" "Antmicro"
			(at 229.87 372.11 0)
			(effects
				(font
					(size 1.27 1.27)
					(thickness 0.15)
				)
				(justify left bottom)
				(hide yes)
			)
		)
		(property "License" "Apache-2.0"
			(at 229.87 374.65 0)
			(effects
				(font
					(size 1.27 1.27)
					(thickness 0.15)
				)
				(justify left bottom)
				(hide yes)
			)
		)
		(pin "1"
		)
		(instances
			(project "thunderbolt-gpu-adapter"
				(path ""
					(reference "#PWR0216")
					(unit 1)
				)
			)
		)
	)
	(symbol
		(lib_id "antmicropower:GND")
		(at 148.59 143.51 0)
		(unit 1)
		(exclude_from_sim no)
		(in_bom yes)
		(on_board yes)
		(dnp no)
		(property "Reference" "#PWR056"
			(at 148.59 149.86 0)
			(effects
				(font
					(size 1.27 1.27)
				)
				(hide yes)
			)
		)
		(property "Value" "GND"
			(at 148.59 147.32 0)
			(effects
				(font
					(size 1.27 1.27)
				)
			)
		)
		(property "Footprint" ""
			(at 148.59 143.51 0)
			(effects
				(font
					(size 1.27 1.27)
				)
				(hide yes)
			)
		)
		(property "Datasheet" ""
			(at 148.59 143.51 0)
			(effects
				(font
					(size 1.27 1.27)
				)
				(hide yes)
			)
		)
		(property "Description" ""
			(at 148.59 143.51 0)
			(effects
				(font
					(size 1.27 1.27)
				)
				(hide yes)
			)
		)
		(property "Author" "Antmicro"
			(at 157.48 151.13 0)
			(effects
				(font
					(size 1.27 1.27)
					(thickness 0.15)
				)
				(justify left bottom)
				(hide yes)
			)
		)
		(property "License" "Apache-2.0"
			(at 157.48 153.67 0)
			(effects
				(font
					(size 1.27 1.27)
					(thickness 0.15)
				)
				(justify left bottom)
				(hide yes)
			)
		)
		(pin "1"
		)
		(instances
			(project "thunderbolt-gpu-adapter"
				(path ""
					(reference "#PWR056")
					(unit 1)
				)
			)
		)
	)
	(symbol
		(lib_id "antmicroCapacitorsmisc:C_22u_1206_35V")
		(at 74.93 337.82 90)
		(unit 1)
		(exclude_from_sim no)
		(in_bom yes)
		(on_board yes)
		(dnp no)
		(fields_autoplaced yes)
		(property "Reference" "C15"
			(at 77.47 334.0036 90)
			(effects
				(font
					(size 1.27 1.27)
					(thickness 0.15)
				)
				(justify right)
			)
		)
		(property "Value" "C_22u_1206_35V"
			(at 85.09 317.5 0)
			(effects
				(font
					(size 1.27 1.27)
					(thickness 0.15)
				)
				(justify left bottom)
				(hide yes)
			)
		)
		(property "Footprint" "antmicro-footprints:C_1206_3216Metric"
			(at 87.63 317.5 0)
			(effects
				(font
					(size 1.27 1.27)
					(thickness 0.15)
				)
				(justify left bottom)
				(hide yes)
			)
		)
		(property "Datasheet" "https://product.tdk.com/en/search/capacitor/ceramic/mlcc/info?part_no=3216X5R1V226M160AC"
			(at 90.17 317.5 0)
			(effects
				(font
					(size 1.27 1.27)
					(thickness 0.15)
				)
				(justify left bottom)
				(hide yes)
			)
		)
		(property "Description" ""
			(at 74.93 337.82 0)
			(effects
				(font
					(size 1.27 1.27)
				)
				(hide yes)
			)
		)
		(property "MPN" "3216X5R1V226M160AC"
			(at 92.71 317.5 0)
			(effects
				(font
					(size 1.27 1.27)
					(thickness 0.15)
				)
				(justify left bottom)
				(hide yes)
			)
		)
		(property "Manufacturer" "TDK"
			(at 95.25 317.5 0)
			(effects
				(font
					(size 1.27 1.27)
					(thickness 0.15)
				)
				(justify left bottom)
				(hide yes)
			)
		)
		(property "License" "Apache-2.0"
			(at 97.79 317.5 0)
			(effects
				(font
					(size 1.27 1.27)
					(thickness 0.15)
				)
				(justify left bottom)
				(hide yes)
			)
		)
		(property "Val" "22u"
			(at 77.47 336.5436 90)
			(effects
				(font
					(size 1.27 1.27)
					(thickness 0.15)
				)
				(justify right)
			)
		)
		(property "Voltage" "35V"
			(at 102.87 317.5 0)
			(effects
				(font
					(size 1.27 1.27)
				)
				(justify left bottom)
				(hide yes)
			)
		)
		(property "Dielectric" ""
			(at 105.41 317.5 0)
			(effects
				(font
					(size 1.27 1.27)
				)
				(justify left bottom)
				(hide yes)
			)
		)
		(property "Author" "Antmicro"
			(at 100.33 317.5 0)
			(effects
				(font
					(size 1.27 1.27)
					(thickness 0.15)
				)
				(justify left bottom)
				(hide yes)
			)
		)
		(pin "1"
		)
		(pin "2"
		)
		(instances
			(project "thunderbolt-gpu-adapter"
				(path ""
					(reference "C15")
					(unit 1)
				)
			)
		)
	)
	(symbol
		(lib_id "antmicropower:GND")
		(at 148.59 116.84 0)
		(unit 1)
		(exclude_from_sim no)
		(in_bom yes)
		(on_board yes)
		(dnp no)
		(property "Reference" "#PWR046"
			(at 148.59 123.19 0)
			(effects
				(font
					(size 1.27 1.27)
				)
				(hide yes)
			)
		)
		(property "Value" "GND"
			(at 148.59 120.65 0)
			(effects
				(font
					(size 1.27 1.27)
				)
			)
		)
		(property "Footprint" ""
			(at 148.59 116.84 0)
			(effects
				(font
					(size 1.27 1.27)
				)
				(hide yes)
			)
		)
		(property "Datasheet" ""
			(at 148.59 116.84 0)
			(effects
				(font
					(size 1.27 1.27)
				)
				(hide yes)
			)
		)
		(property "Description" ""
			(at 148.59 116.84 0)
			(effects
				(font
					(size 1.27 1.27)
				)
				(hide yes)
			)
		)
		(property "Author" "Antmicro"
			(at 157.48 124.46 0)
			(effects
				(font
					(size 1.27 1.27)
					(thickness 0.15)
				)
				(justify left bottom)
				(hide yes)
			)
		)
		(property "License" "Apache-2.0"
			(at 157.48 127 0)
			(effects
				(font
					(size 1.27 1.27)
					(thickness 0.15)
				)
				(justify left bottom)
				(hide yes)
			)
		)
		(pin "1"
		)
		(instances
			(project "thunderbolt-gpu-adapter"
				(path ""
					(reference "#PWR046")
					(unit 1)
				)
			)
		)
	)
	(symbol
		(lib_id "antmicroResistors0402:R_0R_0402")
		(at 119.38 236.22 0)
		(unit 1)
		(exclude_from_sim no)
		(in_bom yes)
		(on_board yes)
		(dnp no)
		(property "Reference" "R12"
			(at 118.11 234.95 0)
			(effects
				(font
					(size 1.27 1.27)
					(thickness 0.15)
				)
			)
		)
		(property "Value" "R_0R_0402"
			(at 139.7 248.92 0)
			(effects
				(font
					(size 1.27 1.27)
					(thickness 0.15)
				)
				(justify left bottom)
				(hide yes)
			)
		)
		(property "Footprint" "antmicro-footprints:R_0402_1005Metric"
			(at 139.7 251.46 0)
			(effects
				(font
					(size 1.27 1.27)
					(thickness 0.15)
				)
				(justify left bottom)
				(hide yes)
			)
		)
		(property "Datasheet" "https://industrial.panasonic.com/cdbs/www-data/pdf/RDA0000/AOA0000C301.pdf"
			(at 139.7 254 0)
			(effects
				(font
					(size 1.27 1.27)
					(thickness 0.15)
				)
				(justify left bottom)
				(hide yes)
			)
		)
		(property "Description" ""
			(at 119.38 236.22 0)
			(effects
				(font
					(size 1.27 1.27)
				)
				(hide yes)
			)
		)
		(property "MPN" "ERJ2GE0R00X"
			(at 139.7 256.54 0)
			(effects
				(font
					(size 1.27 1.27)
					(thickness 0.15)
				)
				(justify left bottom)
				(hide yes)
			)
		)
		(property "Manufacturer" "Panasonic"
			(at 139.7 259.08 0)
			(effects
				(font
					(size 1.27 1.27)
					(thickness 0.15)
				)
				(justify left bottom)
				(hide yes)
			)
		)
		(property "License" "Apache-2.0"
			(at 139.7 261.62 0)
			(effects
				(font
					(size 1.27 1.27)
					(thickness 0.15)
				)
				(justify left bottom)
				(hide yes)
			)
		)
		(property "Val" "0R"
			(at 124.46 235.585 0)
			(effects
				(font
					(size 1.27 1.27)
					(thickness 0.15)
				)
				(justify left bottom)
			)
		)
		(property "Tolerance" "~"
			(at 139.7 246.38 0)
			(effects
				(font
					(size 1.27 1.27)
				)
				(justify left bottom)
				(hide yes)
			)
		)
		(property "Current" "1A"
			(at 139.7 266.7 0)
			(effects
				(font
					(size 1.27 1.27)
					(thickness 0.15)
				)
				(justify left bottom)
				(hide yes)
			)
		)
		(property "Author" "Antmicro"
			(at 139.7 264.16 0)
			(effects
				(font
					(size 1.27 1.27)
					(thickness 0.15)
				)
				(justify left bottom)
				(hide yes)
			)
		)
		(pin "1"
		)
		(pin "2"
		)
		(instances
			(project "thunderbolt-gpu-adapter"
				(path ""
					(reference "R12")
					(unit 1)
				)
			)
		)
	)
	(symbol
		(lib_id "antmicropower:GND")
		(at 163.83 58.42 0)
		(unit 1)
		(exclude_from_sim no)
		(in_bom yes)
		(on_board yes)
		(dnp no)
		(property "Reference" "#PWR0219"
			(at 163.83 64.77 0)
			(effects
				(font
					(size 1.27 1.27)
				)
				(hide yes)
			)
		)
		(property "Value" "GND"
			(at 163.83 62.23 0)
			(effects
				(font
					(size 1.27 1.27)
				)
			)
		)
		(property "Footprint" ""
			(at 163.83 58.42 0)
			(effects
				(font
					(size 1.27 1.27)
				)
				(hide yes)
			)
		)
		(property "Datasheet" ""
			(at 163.83 58.42 0)
			(effects
				(font
					(size 1.27 1.27)
				)
				(hide yes)
			)
		)
		(property "Description" ""
			(at 163.83 58.42 0)
			(effects
				(font
					(size 1.27 1.27)
				)
				(hide yes)
			)
		)
		(property "Author" "Antmicro"
			(at 172.72 66.04 0)
			(effects
				(font
					(size 1.27 1.27)
					(thickness 0.15)
				)
				(justify left bottom)
				(hide yes)
			)
		)
		(property "License" "Apache-2.0"
			(at 172.72 68.58 0)
			(effects
				(font
					(size 1.27 1.27)
					(thickness 0.15)
				)
				(justify left bottom)
				(hide yes)
			)
		)
		(pin "1"
		)
		(instances
			(project "thunderbolt-gpu-adapter"
				(path ""
					(reference "#PWR0219")
					(unit 1)
				)
			)
		)
	)
	(symbol
		(lib_id "antmicroTestPoints:TP_1mm_SMD")
		(at 46.99 257.81 90)
		(unit 1)
		(exclude_from_sim no)
		(in_bom no)
		(on_board yes)
		(dnp no)
		(property "Reference" "TP12"
			(at 45.085 252.73 90)
			(effects
				(font
					(size 1.27 1.27)
					(thickness 0.15)
				)
				(justify right)
			)
		)
		(property "Value" "TP_1mm_SMD"
			(at 48.895 254.6349 90)
			(effects
				(font
					(size 1.27 1.27)
					(thickness 0.15)
				)
				(justify right)
				(hide yes)
			)
		)
		(property "Footprint" "antmicro-footprints:TP_SMD_1mm"
			(at 57.15 242.57 0)
			(effects
				(font
					(size 1.27 1.27)
					(thickness 0.15)
				)
				(justify left bottom)
				(hide yes)
			)
		)
		(property "Datasheet" ""
			(at 59.69 242.57 0)
			(effects
				(font
					(size 1.27 1.27)
					(thickness 0.15)
				)
				(justify left bottom)
				(hide yes)
			)
		)
		(property "Description" ""
			(at 46.99 257.81 0)
			(effects
				(font
					(size 1.27 1.27)
				)
				(hide yes)
			)
		)
		(property "License" "Apache-2.0"
			(at 64.77 242.57 0)
			(effects
				(font
					(size 1.27 1.27)
					(thickness 0.15)
				)
				(justify left bottom)
				(hide yes)
			)
		)
		(property "Manufacturer" ""
			(at 48.895 257.1749 90)
			(effects
				(font
					(size 1.27 1.27)
				)
				(justify right)
				(hide yes)
			)
		)
		(property "MPN" ""
			(at 46.99 257.81 0)
			(effects
				(font
					(size 1.27 1.27)
				)
				(hide yes)
			)
		)
		(property "Author" "Antmicro"
			(at 62.23 242.57 0)
			(effects
				(font
					(size 1.27 1.27)
					(thickness 0.15)
				)
				(justify left bottom)
				(hide yes)
			)
		)
		(pin "1"
		)
		(instances
			(project "thunderbolt-gpu-adapter"
				(path ""
					(reference "TP12")
					(unit 1)
				)
			)
		)
	)
	(symbol
		(lib_id "antmicroLEDIndicationDiscrete:LED_G_0603_KP-1608CGCK")
		(at 224.79 275.59 270)
		(mirror x)
		(unit 1)
		(exclude_from_sim no)
		(in_bom yes)
		(on_board yes)
		(dnp no)
		(property "Reference" "D5"
			(at 222.25 271.78 90)
			(effects
				(font
					(size 1.27 1.27)
					(thickness 0.15)
				)
				(justify right)
			)
		)
		(property "Value" "LED_G_0603_KP-1608CGCK"
			(at 220.98 257.81 0)
			(effects
				(font
					(size 1.27 1.27)
					(thickness 0.15)
				)
				(justify right)
				(hide yes)
			)
		)
		(property "Footprint" "antmicro-footprints:LED_0603_1608Metric_G"
			(at 214.63 252.73 0)
			(effects
				(font
					(size 1.27 1.27)
					(thickness 0.15)
				)
				(justify left bottom)
				(hide yes)
			)
		)
		(property "Datasheet" "http://www.kingbright.com/attachments/file/psearch//000/00/00/KP-1608CGCK(Ver.23B).pdf"
			(at 212.09 252.73 0)
			(effects
				(font
					(size 1.27 1.27)
					(thickness 0.15)
				)
				(justify left bottom)
				(hide yes)
			)
		)
		(property "Description" ""
			(at 224.79 275.59 0)
			(effects
				(font
					(size 1.27 1.27)
				)
				(hide yes)
			)
		)
		(property "MPN" "KP-1608CGCK"
			(at 209.55 252.73 0)
			(effects
				(font
					(size 1.27 1.27)
					(thickness 0.15)
				)
				(justify left bottom)
				(hide yes)
			)
		)
		(property "Manufacturer" "Kingbright"
			(at 207.01 252.73 0)
			(effects
				(font
					(size 1.27 1.27)
					(thickness 0.15)
				)
				(justify left bottom)
				(hide yes)
			)
		)
		(property "License" "Apache-2.0"
			(at 201.93 252.73 0)
			(effects
				(font
					(size 1.27 1.27)
					(thickness 0.15)
				)
				(justify left bottom)
				(hide yes)
			)
		)
		(property "Author" "Antmicro"
			(at 204.47 252.73 0)
			(effects
				(font
					(size 1.27 1.27)
					(thickness 0.15)
				)
				(justify left bottom)
				(hide yes)
			)
		)
		(property "Color" "Green"
			(at 222.25 274.32 90)
			(effects
				(font
					(size 1.27 1.27)
				)
				(justify right)
			)
		)
		(pin "1"
		)
		(pin "2"
		)
		(instances
			(project "thunderbolt-gpu-adapter"
				(path ""
					(reference "D5")
					(unit 1)
				)
			)
		)
	)
	(symbol
		(lib_id "antmicroFerriteBeadsandChips:FB_30Z_8.5A_Murata-BLM21SN_0805")
		(at 45.72 330.2 0)
		(mirror x)
		(unit 1)
		(exclude_from_sim no)
		(in_bom yes)
		(on_board yes)
		(dnp no)
		(fields_autoplaced yes)
		(property "Reference" "FB2"
			(at 48.2219 323.85 0)
			(effects
				(font
					(size 1.27 1.27)
					(thickness 0.15)
				)
			)
		)
		(property "Value" "FB_30Z_8.5A_Murata-BLM21SN_0805"
			(at 47.625 333.375 0)
			(effects
				(font
					(size 1.27 1.27)
					(thickness 0.15)
				)
				(hide yes)
			)
		)
		(property "Footprint" "antmicro-footprints:FB_0805_2012Metric"
			(at 59.69 325.12 0)
			(effects
				(font
					(size 1.27 1.27)
					(thickness 0.15)
				)
				(justify left bottom)
				(hide yes)
			)
		)
		(property "Datasheet" "https://www.murata.com/en-sg/products/productdata/8796738977822/ENFA0005.pdf?1519270210000"
			(at 59.69 322.58 0)
			(effects
				(font
					(size 1.27 1.27)
					(thickness 0.15)
				)
				(justify left bottom)
				(hide yes)
			)
		)
		(property "Description" ""
			(at 45.72 330.2 0)
			(effects
				(font
					(size 1.27 1.27)
				)
				(hide yes)
			)
		)
		(property "MPN" "BLM21SN300SZ1D"
			(at 59.69 320.04 0)
			(effects
				(font
					(size 1.27 1.27)
					(thickness 0.15)
				)
				(justify left bottom)
				(hide yes)
			)
		)
		(property "Manufacturer" "Murata"
			(at 59.69 317.5 0)
			(effects
				(font
					(size 1.27 1.27)
					(thickness 0.15)
				)
				(justify left bottom)
				(hide yes)
			)
		)
		(property "License" "Apache-2.0"
			(at 59.69 312.42 0)
			(effects
				(font
					(size 1.27 1.27)
					(thickness 0.15)
				)
				(justify left bottom)
				(hide yes)
			)
		)
		(property "Author" "Antmicro"
			(at 59.69 314.96 0)
			(effects
				(font
					(size 1.27 1.27)
					(thickness 0.15)
				)
				(justify left bottom)
				(hide yes)
			)
		)
		(property "Val" "30Z/8.5A"
			(at 48.2219 326.39 0)
			(effects
				(font
					(size 1.27 1.27)
				)
			)
		)
		(property "Current" ""
			(at 66.04 307.34 0)
			(effects
				(font
					(size 1.27 1.27)
					(thickness 0.15)
				)
				(justify left bottom)
				(hide yes)
			)
		)
		(pin "1"
		)
		(pin "2"
		)
		(instances
			(project "thunderbolt-gpu-adapter"
				(path ""
					(reference "FB2")
					(unit 1)
				)
			)
		)
	)
	(symbol
		(lib_id "antmicropower:GND")
		(at 27.94 341.63 0)
		(unit 1)
		(exclude_from_sim no)
		(in_bom yes)
		(on_board yes)
		(dnp no)
		(property "Reference" "#PWR0207"
			(at 27.94 347.98 0)
			(effects
				(font
					(size 1.27 1.27)
				)
				(hide yes)
			)
		)
		(property "Value" "GND"
			(at 27.94 345.44 0)
			(effects
				(font
					(size 1.27 1.27)
				)
			)
		)
		(property "Footprint" ""
			(at 27.94 341.63 0)
			(effects
				(font
					(size 1.27 1.27)
				)
				(hide yes)
			)
		)
		(property "Datasheet" ""
			(at 27.94 341.63 0)
			(effects
				(font
					(size 1.27 1.27)
				)
				(hide yes)
			)
		)
		(property "Description" ""
			(at 27.94 341.63 0)
			(effects
				(font
					(size 1.27 1.27)
				)
				(hide yes)
			)
		)
		(property "Author" "Antmicro"
			(at 36.83 349.25 0)
			(effects
				(font
					(size 1.27 1.27)
					(thickness 0.15)
				)
				(justify left bottom)
				(hide yes)
			)
		)
		(property "License" "Apache-2.0"
			(at 36.83 351.79 0)
			(effects
				(font
					(size 1.27 1.27)
					(thickness 0.15)
				)
				(justify left bottom)
				(hide yes)
			)
		)
		(pin "1"
		)
		(instances
			(project "thunderbolt-gpu-adapter"
				(path ""
					(reference "#PWR0207")
					(unit 1)
				)
			)
		)
	)
	(symbol
		(lib_id "antmicropower:GND")
		(at 246.38 128.27 0)
		(unit 1)
		(exclude_from_sim no)
		(in_bom yes)
		(on_board yes)
		(dnp no)
		(property "Reference" "#PWR0196"
			(at 246.38 134.62 0)
			(effects
				(font
					(size 1.27 1.27)
				)
				(hide yes)
			)
		)
		(property "Value" "GND"
			(at 246.38 132.08 0)
			(effects
				(font
					(size 1.27 1.27)
				)
			)
		)
		(property "Footprint" ""
			(at 246.38 128.27 0)
			(effects
				(font
					(size 1.27 1.27)
				)
				(hide yes)
			)
		)
		(property "Datasheet" ""
			(at 246.38 128.27 0)
			(effects
				(font
					(size 1.27 1.27)
				)
				(hide yes)
			)
		)
		(property "Description" ""
			(at 246.38 128.27 0)
			(effects
				(font
					(size 1.27 1.27)
				)
				(hide yes)
			)
		)
		(property "Author" "Antmicro"
			(at 255.27 135.89 0)
			(effects
				(font
					(size 1.27 1.27)
					(thickness 0.15)
				)
				(justify left bottom)
				(hide yes)
			)
		)
		(property "License" "Apache-2.0"
			(at 255.27 138.43 0)
			(effects
				(font
					(size 1.27 1.27)
					(thickness 0.15)
				)
				(justify left bottom)
				(hide yes)
			)
		)
		(pin "1"
		)
		(instances
			(project "thunderbolt-gpu-adapter"
				(path ""
					(reference "#PWR0196")
					(unit 1)
				)
			)
		)
	)
	(symbol
		(lib_id "antmicropower:GND")
		(at 148.59 158.75 0)
		(unit 1)
		(exclude_from_sim no)
		(in_bom yes)
		(on_board yes)
		(dnp no)
		(property "Reference" "#PWR058"
			(at 148.59 165.1 0)
			(effects
				(font
					(size 1.27 1.27)
				)
				(hide yes)
			)
		)
		(property "Value" "GND"
			(at 148.59 162.56 0)
			(effects
				(font
					(size 1.27 1.27)
				)
			)
		)
		(property "Footprint" ""
			(at 148.59 158.75 0)
			(effects
				(font
					(size 1.27 1.27)
				)
				(hide yes)
			)
		)
		(property "Datasheet" ""
			(at 148.59 158.75 0)
			(effects
				(font
					(size 1.27 1.27)
				)
				(hide yes)
			)
		)
		(property "Description" ""
			(at 148.59 158.75 0)
			(effects
				(font
					(size 1.27 1.27)
				)
				(hide yes)
			)
		)
		(property "Author" "Antmicro"
			(at 157.48 166.37 0)
			(effects
				(font
					(size 1.27 1.27)
					(thickness 0.15)
				)
				(justify left bottom)
				(hide yes)
			)
		)
		(property "License" "Apache-2.0"
			(at 157.48 168.91 0)
			(effects
				(font
					(size 1.27 1.27)
					(thickness 0.15)
				)
				(justify left bottom)
				(hide yes)
			)
		)
		(pin "1"
		)
		(instances
			(project "thunderbolt-gpu-adapter"
				(path ""
					(reference "#PWR058")
					(unit 1)
				)
			)
		)
	)
	(symbol
		(lib_id "antmicroResistors0402:R_2k2_0402")
		(at 40.64 68.58 90)
		(unit 1)
		(exclude_from_sim no)
		(in_bom yes)
		(on_board yes)
		(dnp no)
		(property "Reference" "R5"
			(at 41.91 64.77 90)
			(effects
				(font
					(size 1.27 1.27)
					(thickness 0.15)
				)
				(justify right)
			)
		)
		(property "Value" "R_2k2_0402"
			(at 53.34 48.26 0)
			(effects
				(font
					(size 1.27 1.27)
					(thickness 0.15)
				)
				(justify left bottom)
				(hide yes)
			)
		)
		(property "Footprint" "antmicro-footprints:R_0402_1005Metric"
			(at 55.88 48.26 0)
			(effects
				(font
					(size 1.27 1.27)
					(thickness 0.15)
				)
				(justify left bottom)
				(hide yes)
			)
		)
		(property "Datasheet" "https://www.bourns.com/docs/product-datasheets/cr.pdf"
			(at 58.42 48.26 0)
			(effects
				(font
					(size 1.27 1.27)
					(thickness 0.15)
				)
				(justify left bottom)
				(hide yes)
			)
		)
		(property "Description" ""
			(at 40.64 68.58 0)
			(effects
				(font
					(size 1.27 1.27)
				)
				(hide yes)
			)
		)
		(property "MPN" "CR0402-FX-2201GLF"
			(at 60.96 48.26 0)
			(effects
				(font
					(size 1.27 1.27)
					(thickness 0.15)
				)
				(justify left bottom)
				(hide yes)
			)
		)
		(property "Manufacturer" "Bourns"
			(at 63.5 48.26 0)
			(effects
				(font
					(size 1.27 1.27)
					(thickness 0.15)
				)
				(justify left bottom)
				(hide yes)
			)
		)
		(property "License" "Apache-2.0"
			(at 66.04 48.26 0)
			(effects
				(font
					(size 1.27 1.27)
					(thickness 0.15)
				)
				(justify left bottom)
				(hide yes)
			)
		)
		(property "Val" "2k2"
			(at 41.91 67.31 90)
			(effects
				(font
					(size 1.27 1.27)
					(thickness 0.15)
				)
				(justify right)
			)
		)
		(property "Tolerance" "1%"
			(at 50.8 48.26 0)
			(effects
				(font
					(size 1.27 1.27)
				)
				(justify left bottom)
				(hide yes)
			)
		)
		(property "Author" "Antmicro"
			(at 68.58 48.26 0)
			(effects
				(font
					(size 1.27 1.27)
					(thickness 0.15)
				)
				(justify left bottom)
				(hide yes)
			)
		)
		(pin "1"
		)
		(pin "2"
		)
		(instances
			(project "thunderbolt-gpu-adapter"
				(path ""
					(reference "R5")
					(unit 1)
				)
			)
		)
	)
	(symbol
		(lib_id "antmicroCapacitors0603:C_22u_0603")
		(at 181.61 358.14 90)
		(unit 1)
		(exclude_from_sim no)
		(in_bom yes)
		(on_board yes)
		(dnp no)
		(fields_autoplaced yes)
		(property "Reference" "C44"
			(at 184.15 354.3236 90)
			(effects
				(font
					(size 1.27 1.27)
					(thickness 0.15)
				)
				(justify right)
			)
		)
		(property "Value" "C_22u_0603"
			(at 191.77 337.82 0)
			(effects
				(font
					(size 1.27 1.27)
					(thickness 0.15)
				)
				(justify left bottom)
				(hide yes)
			)
		)
		(property "Footprint" "antmicro-footprints:C_0603_1608Metric"
			(at 194.31 337.82 0)
			(effects
				(font
					(size 1.27 1.27)
					(thickness 0.15)
				)
				(justify left bottom)
				(hide yes)
			)
		)
		(property "Datasheet" "https://www.murata.com/products/productdetail?partno=GRM188R60J226MEA0%23"
			(at 196.85 337.82 0)
			(effects
				(font
					(size 1.27 1.27)
					(thickness 0.15)
				)
				(justify left bottom)
				(hide yes)
			)
		)
		(property "Description" ""
			(at 181.61 358.14 0)
			(effects
				(font
					(size 1.27 1.27)
				)
				(hide yes)
			)
		)
		(property "MPN" "GRM188R60J226MEA0D"
			(at 199.39 337.82 0)
			(effects
				(font
					(size 1.27 1.27)
					(thickness 0.15)
				)
				(justify left bottom)
				(hide yes)
			)
		)
		(property "Manufacturer" "Murata"
			(at 201.93 337.82 0)
			(effects
				(font
					(size 1.27 1.27)
					(thickness 0.15)
				)
				(justify left bottom)
				(hide yes)
			)
		)
		(property "License" "Apache-2.0"
			(at 204.47 337.82 0)
			(effects
				(font
					(size 1.27 1.27)
					(thickness 0.15)
				)
				(justify left bottom)
				(hide yes)
			)
		)
		(property "Val" "22u"
			(at 184.15 356.8636 90)
			(effects
				(font
					(size 1.27 1.27)
					(thickness 0.15)
				)
				(justify right)
			)
		)
		(property "Voltage" ""
			(at 209.55 337.82 0)
			(effects
				(font
					(size 1.27 1.27)
				)
				(justify left bottom)
				(hide yes)
			)
		)
		(property "Dielectric" ""
			(at 212.09 337.82 0)
			(effects
				(font
					(size 1.27 1.27)
				)
				(justify left bottom)
				(hide yes)
			)
		)
		(property "Author" "Antmicro"
			(at 207.01 337.82 0)
			(effects
				(font
					(size 1.27 1.27)
					(thickness 0.15)
				)
				(justify left bottom)
				(hide yes)
			)
		)
		(pin "1"
		)
		(pin "2"
		)
		(instances
			(project "thunderbolt-gpu-adapter"
				(path ""
					(reference "C44")
					(unit 1)
				)
			)
		)
	)
	(symbol
		(lib_id "antmicropower:GND")
		(at 182.88 58.42 0)
		(unit 1)
		(exclude_from_sim no)
		(in_bom yes)
		(on_board yes)
		(dnp no)
		(property "Reference" "#PWR069"
			(at 182.88 64.77 0)
			(effects
				(font
					(size 1.27 1.27)
				)
				(hide yes)
			)
		)
		(property "Value" "GND"
			(at 182.88 62.23 0)
			(effects
				(font
					(size 1.27 1.27)
				)
			)
		)
		(property "Footprint" ""
			(at 182.88 58.42 0)
			(effects
				(font
					(size 1.27 1.27)
				)
				(hide yes)
			)
		)
		(property "Datasheet" ""
			(at 182.88 58.42 0)
			(effects
				(font
					(size 1.27 1.27)
				)
				(hide yes)
			)
		)
		(property "Description" ""
			(at 182.88 58.42 0)
			(effects
				(font
					(size 1.27 1.27)
				)
				(hide yes)
			)
		)
		(property "Author" "Antmicro"
			(at 191.77 66.04 0)
			(effects
				(font
					(size 1.27 1.27)
					(thickness 0.15)
				)
				(justify left bottom)
				(hide yes)
			)
		)
		(property "License" "Apache-2.0"
			(at 191.77 68.58 0)
			(effects
				(font
					(size 1.27 1.27)
					(thickness 0.15)
				)
				(justify left bottom)
				(hide yes)
			)
		)
		(pin "1"
		)
		(instances
			(project "thunderbolt-gpu-adapter"
				(path ""
					(reference "#PWR069")
					(unit 1)
				)
			)
		)
	)
	(symbol
		(lib_id "antmicropower:GND")
		(at 46.99 267.97 0)
		(unit 1)
		(exclude_from_sim no)
		(in_bom yes)
		(on_board yes)
		(dnp no)
		(property "Reference" "#PWR0165"
			(at 46.99 274.32 0)
			(effects
				(font
					(size 1.27 1.27)
				)
				(hide yes)
			)
		)
		(property "Value" "GND"
			(at 46.99 271.78 0)
			(effects
				(font
					(size 1.27 1.27)
				)
			)
		)
		(property "Footprint" ""
			(at 46.99 267.97 0)
			(effects
				(font
					(size 1.27 1.27)
				)
				(hide yes)
			)
		)
		(property "Datasheet" ""
			(at 46.99 267.97 0)
			(effects
				(font
					(size 1.27 1.27)
				)
				(hide yes)
			)
		)
		(property "Description" ""
			(at 46.99 267.97 0)
			(effects
				(font
					(size 1.27 1.27)
				)
				(hide yes)
			)
		)
		(property "Author" "Antmicro"
			(at 55.88 275.59 0)
			(effects
				(font
					(size 1.27 1.27)
					(thickness 0.15)
				)
				(justify left bottom)
				(hide yes)
			)
		)
		(property "License" "Apache-2.0"
			(at 55.88 278.13 0)
			(effects
				(font
					(size 1.27 1.27)
					(thickness 0.15)
				)
				(justify left bottom)
				(hide yes)
			)
		)
		(pin "1"
		)
		(instances
			(project "thunderbolt-gpu-adapter"
				(path ""
					(reference "#PWR0165")
					(unit 1)
				)
			)
		)
	)
	(symbol
		(lib_id "antmicroResistors0402:R_0R_0402")
		(at 119.38 238.76 0)
		(mirror x)
		(unit 1)
		(exclude_from_sim no)
		(in_bom yes)
		(on_board yes)
		(dnp no)
		(property "Reference" "R13"
			(at 118.11 237.49 0)
			(effects
				(font
					(size 1.27 1.27)
					(thickness 0.15)
				)
			)
		)
		(property "Value" "R_0R_0402"
			(at 139.7 226.06 0)
			(effects
				(font
					(size 1.27 1.27)
					(thickness 0.15)
				)
				(justify left bottom)
				(hide yes)
			)
		)
		(property "Footprint" "antmicro-footprints:R_0402_1005Metric"
			(at 139.7 223.52 0)
			(effects
				(font
					(size 1.27 1.27)
					(thickness 0.15)
				)
				(justify left bottom)
				(hide yes)
			)
		)
		(property "Datasheet" "https://industrial.panasonic.com/cdbs/www-data/pdf/RDA0000/AOA0000C301.pdf"
			(at 139.7 220.98 0)
			(effects
				(font
					(size 1.27 1.27)
					(thickness 0.15)
				)
				(justify left bottom)
				(hide yes)
			)
		)
		(property "Description" ""
			(at 119.38 238.76 0)
			(effects
				(font
					(size 1.27 1.27)
				)
				(hide yes)
			)
		)
		(property "MPN" "ERJ2GE0R00X"
			(at 139.7 218.44 0)
			(effects
				(font
					(size 1.27 1.27)
					(thickness 0.15)
				)
				(justify left bottom)
				(hide yes)
			)
		)
		(property "Manufacturer" "Panasonic"
			(at 139.7 215.9 0)
			(effects
				(font
					(size 1.27 1.27)
					(thickness 0.15)
				)
				(justify left bottom)
				(hide yes)
			)
		)
		(property "License" "Apache-2.0"
			(at 139.7 213.36 0)
			(effects
				(font
					(size 1.27 1.27)
					(thickness 0.15)
				)
				(justify left bottom)
				(hide yes)
			)
		)
		(property "Val" "0R"
			(at 124.46 236.855 0)
			(effects
				(font
					(size 1.27 1.27)
					(thickness 0.15)
				)
				(justify left bottom)
			)
		)
		(property "Tolerance" "~"
			(at 139.7 228.6 0)
			(effects
				(font
					(size 1.27 1.27)
				)
				(justify left bottom)
				(hide yes)
			)
		)
		(property "Current" "1A"
			(at 139.7 208.28 0)
			(effects
				(font
					(size 1.27 1.27)
					(thickness 0.15)
				)
				(justify left bottom)
				(hide yes)
			)
		)
		(property "Author" "Antmicro"
			(at 139.7 210.82 0)
			(effects
				(font
					(size 1.27 1.27)
					(thickness 0.15)
				)
				(justify left bottom)
				(hide yes)
			)
		)
		(pin "1"
		)
		(pin "2"
		)
		(instances
			(project "thunderbolt-gpu-adapter"
				(path ""
					(reference "R13")
					(unit 1)
				)
			)
		)
	)
	(symbol
		(lib_id "antmicropower:GND")
		(at 46.99 175.26 0)
		(unit 1)
		(exclude_from_sim no)
		(in_bom yes)
		(on_board yes)
		(dnp no)
		(property "Reference" "#PWR022"
			(at 46.99 181.61 0)
			(effects
				(font
					(size 1.27 1.27)
				)
				(hide yes)
			)
		)
		(property "Value" "GND"
			(at 46.99 179.07 0)
			(effects
				(font
					(size 1.27 1.27)
				)
			)
		)
		(property "Footprint" ""
			(at 46.99 175.26 0)
			(effects
				(font
					(size 1.27 1.27)
				)
				(hide yes)
			)
		)
		(property "Datasheet" ""
			(at 46.99 175.26 0)
			(effects
				(font
					(size 1.27 1.27)
				)
				(hide yes)
			)
		)
		(property "Description" ""
			(at 46.99 175.26 0)
			(effects
				(font
					(size 1.27 1.27)
				)
				(hide yes)
			)
		)
		(property "Author" "Antmicro"
			(at 55.88 182.88 0)
			(effects
				(font
					(size 1.27 1.27)
					(thickness 0.15)
				)
				(justify left bottom)
				(hide yes)
			)
		)
		(property "License" "Apache-2.0"
			(at 55.88 185.42 0)
			(effects
				(font
					(size 1.27 1.27)
					(thickness 0.15)
				)
				(justify left bottom)
				(hide yes)
			)
		)
		(pin "1"
		)
		(instances
			(project "thunderbolt-gpu-adapter"
				(path ""
					(reference "#PWR022")
					(unit 1)
				)
			)
		)
	)
	(symbol
		(lib_id "antmicroTestPoints:TP_1mm_SMD")
		(at 36.83 328.93 90)
		(unit 1)
		(exclude_from_sim no)
		(in_bom no)
		(on_board yes)
		(dnp no)
		(property "Reference" "TP1"
			(at 34.925 323.85 90)
			(effects
				(font
					(size 1.27 1.27)
					(thickness 0.15)
				)
				(justify right)
			)
		)
		(property "Value" "TP_1mm_SMD"
			(at 38.735 325.7549 90)
			(effects
				(font
					(size 1.27 1.27)
					(thickness 0.15)
				)
				(justify right)
				(hide yes)
			)
		)
		(property "Footprint" "antmicro-footprints:TP_SMD_1mm"
			(at 46.99 313.69 0)
			(effects
				(font
					(size 1.27 1.27)
					(thickness 0.15)
				)
				(justify left bottom)
				(hide yes)
			)
		)
		(property "Datasheet" ""
			(at 49.53 313.69 0)
			(effects
				(font
					(size 1.27 1.27)
					(thickness 0.15)
				)
				(justify left bottom)
				(hide yes)
			)
		)
		(property "Description" ""
			(at 36.83 328.93 0)
			(effects
				(font
					(size 1.27 1.27)
				)
				(hide yes)
			)
		)
		(property "License" "Apache-2.0"
			(at 54.61 313.69 0)
			(effects
				(font
					(size 1.27 1.27)
					(thickness 0.15)
				)
				(justify left bottom)
				(hide yes)
			)
		)
		(property "Manufacturer" ""
			(at 38.735 328.2949 90)
			(effects
				(font
					(size 1.27 1.27)
				)
				(justify right)
				(hide yes)
			)
		)
		(property "MPN" ""
			(at 36.83 328.93 0)
			(effects
				(font
					(size 1.27 1.27)
				)
				(hide yes)
			)
		)
		(property "Author" "Antmicro"
			(at 52.07 313.69 0)
			(effects
				(font
					(size 1.27 1.27)
					(thickness 0.15)
				)
				(justify left bottom)
				(hide yes)
			)
		)
		(pin "1"
		)
		(instances
			(project "thunderbolt-gpu-adapter"
				(path ""
					(reference "TP1")
					(unit 1)
				)
			)
		)
	)
	(symbol
		(lib_id "antmicropower:GND")
		(at 148.59 49.53 0)
		(unit 1)
		(exclude_from_sim no)
		(in_bom yes)
		(on_board yes)
		(dnp no)
		(property "Reference" "#PWR050"
			(at 148.59 55.88 0)
			(effects
				(font
					(size 1.27 1.27)
				)
				(hide yes)
			)
		)
		(property "Value" "GND"
			(at 148.59 53.34 0)
			(effects
				(font
					(size 1.27 1.27)
				)
			)
		)
		(property "Footprint" ""
			(at 148.59 49.53 0)
			(effects
				(font
					(size 1.27 1.27)
				)
				(hide yes)
			)
		)
		(property "Datasheet" ""
			(at 148.59 49.53 0)
			(effects
				(font
					(size 1.27 1.27)
				)
				(hide yes)
			)
		)
		(property "Description" ""
			(at 148.59 49.53 0)
			(effects
				(font
					(size 1.27 1.27)
				)
				(hide yes)
			)
		)
		(property "Author" "Antmicro"
			(at 157.48 57.15 0)
			(effects
				(font
					(size 1.27 1.27)
					(thickness 0.15)
				)
				(justify left bottom)
				(hide yes)
			)
		)
		(property "License" "Apache-2.0"
			(at 157.48 59.69 0)
			(effects
				(font
					(size 1.27 1.27)
					(thickness 0.15)
				)
				(justify left bottom)
				(hide yes)
			)
		)
		(pin "1"
		)
		(instances
			(project "thunderbolt-gpu-adapter"
				(path ""
					(reference "#PWR050")
					(unit 1)
				)
			)
		)
	)
	(symbol
		(lib_id "antmicropower:GND")
		(at 251.46 287.02 0)
		(unit 1)
		(exclude_from_sim no)
		(in_bom yes)
		(on_board yes)
		(dnp no)
		(property "Reference" "#PWR0156"
			(at 251.46 293.37 0)
			(effects
				(font
					(size 1.27 1.27)
				)
				(hide yes)
			)
		)
		(property "Value" "GND"
			(at 248.92 290.83 0)
			(effects
				(font
					(size 1.27 1.27)
				)
				(justify left)
			)
		)
		(property "Footprint" ""
			(at 251.46 287.02 0)
			(effects
				(font
					(size 1.27 1.27)
				)
				(hide yes)
			)
		)
		(property "Datasheet" ""
			(at 251.46 287.02 0)
			(effects
				(font
					(size 1.27 1.27)
				)
				(hide yes)
			)
		)
		(property "Description" ""
			(at 251.46 287.02 0)
			(effects
				(font
					(size 1.27 1.27)
				)
				(hide yes)
			)
		)
		(property "Author" "Antmicro"
			(at 260.35 294.64 0)
			(effects
				(font
					(size 1.27 1.27)
					(thickness 0.15)
				)
				(justify left bottom)
				(hide yes)
			)
		)
		(property "License" "Apache-2.0"
			(at 260.35 297.18 0)
			(effects
				(font
					(size 1.27 1.27)
					(thickness 0.15)
				)
				(justify left bottom)
				(hide yes)
			)
		)
		(pin "1"
		)
		(instances
			(project "thunderbolt-gpu-adapter"
				(path ""
					(reference "#PWR0156")
					(unit 1)
				)
			)
		)
	)
	(symbol
		(lib_id "antmicroCapacitors0402:C_22n_0402")
		(at 111.76 228.6 270)
		(mirror x)
		(unit 1)
		(exclude_from_sim no)
		(in_bom yes)
		(on_board yes)
		(dnp no)
		(property "Reference" "C19"
			(at 109.22 224.7836 90)
			(effects
				(font
					(size 1.27 1.27)
					(thickness 0.15)
				)
				(justify right)
			)
		)
		(property "Value" "C_22n_0402"
			(at 101.6 208.28 0)
			(effects
				(font
					(size 1.27 1.27)
					(thickness 0.15)
				)
				(justify left bottom)
				(hide yes)
			)
		)
		(property "Footprint" "antmicro-footprints:C_0402_1005Metric"
			(at 99.06 208.28 0)
			(effects
				(font
					(size 1.27 1.27)
					(thickness 0.15)
				)
				(justify left bottom)
				(hide yes)
			)
		)
		(property "Datasheet" "https://www.murata.com/products/productdetail?partno=GCM155R71H223MA55%23"
			(at 96.52 208.28 0)
			(effects
				(font
					(size 1.27 1.27)
					(thickness 0.15)
				)
				(justify left bottom)
				(hide yes)
			)
		)
		(property "Description" ""
			(at 111.76 228.6 0)
			(effects
				(font
					(size 1.27 1.27)
				)
				(hide yes)
			)
		)
		(property "MPN" "GCM155R71H223MA55D"
			(at 93.98 208.28 0)
			(effects
				(font
					(size 1.27 1.27)
					(thickness 0.15)
				)
				(justify left bottom)
				(hide yes)
			)
		)
		(property "Manufacturer" "Murata"
			(at 91.44 208.28 0)
			(effects
				(font
					(size 1.27 1.27)
					(thickness 0.15)
				)
				(justify left bottom)
				(hide yes)
			)
		)
		(property "License" "Apache-2.0"
			(at 88.9 208.28 0)
			(effects
				(font
					(size 1.27 1.27)
					(thickness 0.15)
				)
				(justify left bottom)
				(hide yes)
			)
		)
		(property "Val" "22n"
			(at 109.22 227.3236 90)
			(effects
				(font
					(size 1.27 1.27)
					(thickness 0.15)
				)
				(justify right)
			)
		)
		(property "Voltage" ""
			(at 83.82 208.28 0)
			(effects
				(font
					(size 1.27 1.27)
				)
				(justify left bottom)
				(hide yes)
			)
		)
		(property "Dielectric" ""
			(at 81.28 208.28 0)
			(effects
				(font
					(size 1.27 1.27)
				)
				(justify left bottom)
				(hide yes)
			)
		)
		(property "Author" "Antmicro"
			(at 86.36 208.28 0)
			(effects
				(font
					(size 1.27 1.27)
					(thickness 0.15)
				)
				(justify left bottom)
				(hide yes)
			)
		)
		(pin "1"
		)
		(pin "2"
		)
		(instances
			(project "thunderbolt-gpu-adapter"
				(path ""
					(reference "C19")
					(unit 1)
				)
			)
		)
	)
	(symbol
		(lib_id "antmicropower:GND")
		(at 36.83 341.63 0)
		(unit 1)
		(exclude_from_sim no)
		(in_bom yes)
		(on_board yes)
		(dnp no)
		(property "Reference" "#PWR015"
			(at 36.83 347.98 0)
			(effects
				(font
					(size 1.27 1.27)
				)
				(hide yes)
			)
		)
		(property "Value" "GND"
			(at 36.83 345.44 0)
			(effects
				(font
					(size 1.27 1.27)
				)
			)
		)
		(property "Footprint" ""
			(at 36.83 341.63 0)
			(effects
				(font
					(size 1.27 1.27)
				)
				(hide yes)
			)
		)
		(property "Datasheet" ""
			(at 36.83 341.63 0)
			(effects
				(font
					(size 1.27 1.27)
				)
				(hide yes)
			)
		)
		(property "Description" ""
			(at 36.83 341.63 0)
			(effects
				(font
					(size 1.27 1.27)
				)
				(hide yes)
			)
		)
		(property "Author" "Antmicro"
			(at 45.72 349.25 0)
			(effects
				(font
					(size 1.27 1.27)
					(thickness 0.15)
				)
				(justify left bottom)
				(hide yes)
			)
		)
		(property "License" "Apache-2.0"
			(at 45.72 351.79 0)
			(effects
				(font
					(size 1.27 1.27)
					(thickness 0.15)
				)
				(justify left bottom)
				(hide yes)
			)
		)
		(pin "1"
		)
		(instances
			(project "thunderbolt-gpu-adapter"
				(path ""
					(reference "#PWR015")
					(unit 1)
				)
			)
		)
	)
	(symbol
		(lib_id "antmicroShuntsJumpers:Net-Tie_P0.127mm")
		(at 240.03 205.74 270)
		(unit 1)
		(exclude_from_sim no)
		(in_bom no)
		(on_board yes)
		(dnp no)
		(property "Reference" "TP10"
			(at 240.665 208.915 90)
			(effects
				(font
					(size 1.27 1.27)
					(thickness 0.15)
				)
				(justify left)
			)
		)
		(property "Value" "Net-Tie_P0.127mm"
			(at 238.76 213.36 90)
			(effects
				(font
					(size 1.27 1.27)
					(thickness 0.15)
				)
				(justify left)
				(hide yes)
			)
		)
		(property "Footprint" "antmicro-footprints:NetTie-2_SMD_Pad0.127mm"
			(at 227.33 227.33 0)
			(effects
				(font
					(size 1.27 1.27)
					(thickness 0.15)
				)
				(justify left bottom)
				(hide yes)
			)
		)
		(property "Datasheet" ""
			(at 224.79 227.33 0)
			(effects
				(font
					(size 1.27 1.27)
					(thickness 0.15)
				)
				(justify left bottom)
				(hide yes)
			)
		)
		(property "Description" ""
			(at 240.03 205.74 0)
			(effects
				(font
					(size 1.27 1.27)
				)
				(hide yes)
			)
		)
		(property "MPN" ""
			(at 229.87 227.33 0)
			(effects
				(font
					(size 1.27 1.27)
					(thickness 0.15)
				)
				(justify left bottom)
			)
		)
		(property "Manufacturer" ""
			(at 222.25 227.33 0)
			(effects
				(font
					(size 1.27 1.27)
					(thickness 0.15)
				)
				(justify left bottom)
				(hide yes)
			)
		)
		(property "Author" "Antmicro"
			(at 219.71 227.33 0)
			(effects
				(font
					(size 1.27 1.27)
					(thickness 0.15)
				)
				(justify left bottom)
				(hide yes)
			)
		)
		(property "License" "Apache-2.0"
			(at 217.17 227.33 0)
			(effects
				(font
					(size 1.27 1.27)
					(thickness 0.15)
				)
				(justify left bottom)
				(hide yes)
			)
		)
		(pin "1"
		)
		(pin "2"
		)
		(instances
			(project "thunderbolt-gpu-adapter"
				(path ""
					(reference "TP10")
					(unit 1)
				)
			)
		)
	)
	(symbol
		(lib_id "antmicroResistors0402:R_124k_0402")
		(at 167.64 250.19 270)
		(mirror x)
		(unit 1)
		(exclude_from_sim no)
		(in_bom yes)
		(on_board yes)
		(dnp no)
		(property "Reference" "R28"
			(at 165.1 246.38 90)
			(effects
				(font
					(size 1.27 1.27)
					(thickness 0.15)
				)
				(justify right)
			)
		)
		(property "Value" "R_124k_0402"
			(at 154.94 229.87 0)
			(effects
				(font
					(size 1.27 1.27)
					(thickness 0.15)
				)
				(justify left bottom)
				(hide yes)
			)
		)
		(property "Footprint" "antmicro-footprints:R_0402_1005Metric"
			(at 152.4 229.87 0)
			(effects
				(font
					(size 1.27 1.27)
					(thickness 0.15)
				)
				(justify left bottom)
				(hide yes)
			)
		)
		(property "Datasheet" "https://www.bourns.com/docs/product-datasheets/cr.pdf"
			(at 149.86 229.87 0)
			(effects
				(font
					(size 1.27 1.27)
					(thickness 0.15)
				)
				(justify left bottom)
				(hide yes)
			)
		)
		(property "Description" ""
			(at 167.64 250.19 0)
			(effects
				(font
					(size 1.27 1.27)
				)
				(hide yes)
			)
		)
		(property "MPN" "CR0402-FX-1243GLF"
			(at 147.32 229.87 0)
			(effects
				(font
					(size 1.27 1.27)
					(thickness 0.15)
				)
				(justify left bottom)
				(hide yes)
			)
		)
		(property "Manufacturer" "Bourns"
			(at 144.78 229.87 0)
			(effects
				(font
					(size 1.27 1.27)
					(thickness 0.15)
				)
				(justify left bottom)
				(hide yes)
			)
		)
		(property "License" "Apache-2.0"
			(at 142.24 229.87 0)
			(effects
				(font
					(size 1.27 1.27)
					(thickness 0.15)
				)
				(justify left bottom)
				(hide yes)
			)
		)
		(property "Author" "Antmicro"
			(at 139.7 229.87 0)
			(effects
				(font
					(size 1.27 1.27)
					(thickness 0.15)
				)
				(justify left bottom)
				(hide yes)
			)
		)
		(property "Val" "124k"
			(at 165.1 248.92 90)
			(effects
				(font
					(size 1.27 1.27)
					(thickness 0.15)
				)
				(justify right)
			)
		)
		(property "Tolerance" "1%"
			(at 157.48 229.87 0)
			(effects
				(font
					(size 1.27 1.27)
				)
				(justify left bottom)
				(hide yes)
			)
		)
		(pin "1"
		)
		(pin "2"
		)
		(instances
			(project "thunderbolt-gpu-adapter"
				(path ""
					(reference "R28")
					(unit 1)
				)
			)
		)
	)
	(symbol
		(lib_id "antmicroCapacitorsmisc:C_10u_0805_35V")
		(at 66.04 204.47 270)
		(mirror x)
		(unit 1)
		(exclude_from_sim no)
		(in_bom yes)
		(on_board yes)
		(dnp no)
		(fields_autoplaced yes)
		(property "Reference" "C11"
			(at 68.58 200.6536 90)
			(effects
				(font
					(size 1.27 1.27)
					(thickness 0.15)
				)
				(justify left)
			)
		)
		(property "Value" "C_10u_0805_35V"
			(at 55.88 184.15 0)
			(effects
				(font
					(size 1.27 1.27)
					(thickness 0.15)
				)
				(justify left bottom)
				(hide yes)
			)
		)
		(property "Footprint" "antmicro-footprints:C_0805_2012Metric"
			(at 53.34 184.15 0)
			(effects
				(font
					(size 1.27 1.27)
					(thickness 0.15)
				)
				(justify left bottom)
				(hide yes)
			)
		)
		(property "Datasheet" "https://www.murata.com/products/productdetail?partno=GRM21BR6YA106KE43%23"
			(at 50.8 184.15 0)
			(effects
				(font
					(size 1.27 1.27)
					(thickness 0.15)
				)
				(justify left bottom)
				(hide yes)
			)
		)
		(property "Description" ""
			(at 66.04 204.47 0)
			(effects
				(font
					(size 1.27 1.27)
				)
				(hide yes)
			)
		)
		(property "MPN" "GRM21BR6YA106KE43L"
			(at 48.26 184.15 0)
			(effects
				(font
					(size 1.27 1.27)
					(thickness 0.15)
				)
				(justify left bottom)
				(hide yes)
			)
		)
		(property "Manufacturer" "Murata"
			(at 45.72 184.15 0)
			(effects
				(font
					(size 1.27 1.27)
					(thickness 0.15)
				)
				(justify left bottom)
				(hide yes)
			)
		)
		(property "License" "Apache-2.0"
			(at 43.18 184.15 0)
			(effects
				(font
					(size 1.27 1.27)
					(thickness 0.15)
				)
				(justify left bottom)
				(hide yes)
			)
		)
		(property "Val" "10u"
			(at 68.58 203.1936 90)
			(effects
				(font
					(size 1.27 1.27)
					(thickness 0.15)
				)
				(justify left)
			)
		)
		(property "Voltage" "35V"
			(at 38.1 184.15 0)
			(effects
				(font
					(size 1.27 1.27)
				)
				(justify left bottom)
				(hide yes)
			)
		)
		(property "Dielectric" ""
			(at 35.56 184.15 0)
			(effects
				(font
					(size 1.27 1.27)
				)
				(justify left bottom)
				(hide yes)
			)
		)
		(property "Author" "Antmicro"
			(at 40.64 184.15 0)
			(effects
				(font
					(size 1.27 1.27)
					(thickness 0.15)
				)
				(justify left bottom)
				(hide yes)
			)
		)
		(pin "1"
		)
		(pin "2"
		)
		(instances
			(project "thunderbolt-gpu-adapter"
				(path ""
					(reference "C11")
					(unit 1)
				)
			)
		)
	)
	(symbol
		(lib_id "antmicroDCDCConverters:LT8350RV")
		(at 130.81 203.2 0)
		(unit 1)
		(exclude_from_sim no)
		(in_bom yes)
		(on_board yes)
		(dnp no)
		(property "Reference" "U1"
			(at 143.51 196.85 0)
			(effects
				(font
					(size 1.27 1.27)
				)
			)
		)
		(property "Value" "LT8350RV"
			(at 187.96 213.36 0)
			(effects
				(font
					(size 1.27 1.27)
					(thickness 0.15)
				)
				(justify left bottom)
				(hide yes)
			)
		)
		(property "Footprint" "antmicro-footprints:QFN-32-4EP_4x6mm_P0.5mm"
			(at 187.96 215.9 0)
			(effects
				(font
					(size 1.27 1.27)
					(thickness 0.15)
				)
				(justify left bottom)
				(hide yes)
			)
		)
		(property "Datasheet" "https://www.analog.com/media/en/technical-documentation/data-sheets/lt8350.pdf"
			(at 187.96 218.44 0)
			(effects
				(font
					(size 1.27 1.27)
					(thickness 0.15)
				)
				(justify left bottom)
				(hide yes)
			)
		)
		(property "Description" ""
			(at 130.81 203.2 0)
			(effects
				(font
					(size 1.27 1.27)
				)
				(hide yes)
			)
		)
		(property "MPN" "LT8350RV#PBF"
			(at 135.89 199.39 0)
			(effects
				(font
					(size 1.27 1.27)
					(thickness 0.15)
				)
				(justify left bottom)
			)
		)
		(property "Manufacturer" "Analog Devices"
			(at 187.96 220.98 0)
			(effects
				(font
					(size 1.27 1.27)
					(thickness 0.15)
				)
				(justify left bottom)
				(hide yes)
			)
		)
		(property "License" "Apache-2.0"
			(at 187.96 223.52 0)
			(effects
				(font
					(size 1.27 1.27)
					(thickness 0.15)
				)
				(justify left bottom)
				(hide yes)
			)
		)
		(property "Author" "Antmicro"
			(at 187.96 226.06 0)
			(effects
				(font
					(size 1.27 1.27)
					(thickness 0.15)
				)
				(justify left bottom)
				(hide yes)
			)
		)
		(pin "10"
		)
		(pin "11"
		)
		(pin "12"
		)
		(pin "13"
		)
		(pin "14"
		)
		(pin "15"
		)
		(pin "16"
		)
		(pin "17"
		)
		(pin "18"
		)
		(pin "19"
		)
		(pin "2"
		)
		(pin "20"
		)
		(pin "21"
		)
		(pin "22"
		)
		(pin "24"
		)
		(pin "25"
		)
		(pin "27"
		)
		(pin "28"
		)
		(pin "29"
		)
		(pin "3"
		)
		(pin "30"
		)
		(pin "31"
		)
		(pin "32"
		)
		(pin "33"
		)
		(pin "34"
		)
		(pin "35"
		)
		(pin "36"
		)
		(pin "5"
		)
		(pin "6"
		)
		(pin "7"
		)
		(pin "8"
		)
		(pin "9"
		)
		(pin "MP"
		)
		(instances
			(project "thunderbolt-gpu-adapter"
				(path ""
					(reference "U1")
					(unit 1)
				)
			)
		)
	)
	(symbol
		(lib_id "antmicroCapacitors0402:C_100n_0402")
		(at 172.72 207.01 270)
		(unit 1)
		(exclude_from_sim no)
		(in_bom yes)
		(on_board yes)
		(dnp no)
		(fields_autoplaced yes)
		(property "Reference" "C29"
			(at 170.18 208.2863 90)
			(effects
				(font
					(size 1.27 1.27)
					(thickness 0.15)
				)
				(justify right)
			)
		)
		(property "Value" "C_100n_0402"
			(at 162.56 227.33 0)
			(effects
				(font
					(size 1.27 1.27)
					(thickness 0.15)
				)
				(justify left bottom)
				(hide yes)
			)
		)
		(property "Footprint" "antmicro-footprints:C_0402_1005Metric"
			(at 160.02 227.33 0)
			(effects
				(font
					(size 1.27 1.27)
					(thickness 0.15)
				)
				(justify left bottom)
				(hide yes)
			)
		)
		(property "Datasheet" "https://www.murata.com/products/productdetail?partno=GRM155R61H104KE14%23"
			(at 157.48 227.33 0)
			(effects
				(font
					(size 1.27 1.27)
					(thickness 0.15)
				)
				(justify left bottom)
				(hide yes)
			)
		)
		(property "Description" ""
			(at 172.72 207.01 0)
			(effects
				(font
					(size 1.27 1.27)
				)
				(hide yes)
			)
		)
		(property "MPN" "GRM155R61H104KE14D"
			(at 154.94 227.33 0)
			(effects
				(font
					(size 1.27 1.27)
					(thickness 0.15)
				)
				(justify left bottom)
				(hide yes)
			)
		)
		(property "Manufacturer" "Murata"
			(at 152.4 227.33 0)
			(effects
				(font
					(size 1.27 1.27)
					(thickness 0.15)
				)
				(justify left bottom)
				(hide yes)
			)
		)
		(property "License" "Apache-2.0"
			(at 149.86 227.33 0)
			(effects
				(font
					(size 1.27 1.27)
					(thickness 0.15)
				)
				(justify left bottom)
				(hide yes)
			)
		)
		(property "Val" "100n"
			(at 170.18 210.8263 90)
			(effects
				(font
					(size 1.27 1.27)
					(thickness 0.15)
				)
				(justify right)
			)
		)
		(property "Voltage" "50V"
			(at 144.78 227.33 0)
			(effects
				(font
					(size 1.27 1.27)
				)
				(justify left bottom)
				(hide yes)
			)
		)
		(property "Dielectric" "X5R"
			(at 142.24 227.33 0)
			(effects
				(font
					(size 1.27 1.27)
				)
				(justify left bottom)
				(hide yes)
			)
		)
		(property "Author" "Antmicro"
			(at 147.32 227.33 0)
			(effects
				(font
					(size 1.27 1.27)
					(thickness 0.15)
				)
				(justify left bottom)
				(hide yes)
			)
		)
		(pin "1"
		)
		(pin "2"
		)
		(instances
			(project "thunderbolt-gpu-adapter"
				(path ""
					(reference "C29")
					(unit 1)
				)
			)
		)
	)
	(symbol
		(lib_id "antmicropower:GND")
		(at 148.59 148.59 0)
		(unit 1)
		(exclude_from_sim no)
		(in_bom yes)
		(on_board yes)
		(dnp no)
		(property "Reference" "#PWR057"
			(at 148.59 154.94 0)
			(effects
				(font
					(size 1.27 1.27)
				)
				(hide yes)
			)
		)
		(property "Value" "GND"
			(at 148.59 152.4 0)
			(effects
				(font
					(size 1.27 1.27)
				)
			)
		)
		(property "Footprint" ""
			(at 148.59 148.59 0)
			(effects
				(font
					(size 1.27 1.27)
				)
				(hide yes)
			)
		)
		(property "Datasheet" ""
			(at 148.59 148.59 0)
			(effects
				(font
					(size 1.27 1.27)
				)
				(hide yes)
			)
		)
		(property "Description" ""
			(at 148.59 148.59 0)
			(effects
				(font
					(size 1.27 1.27)
				)
				(hide yes)
			)
		)
		(property "Author" "Antmicro"
			(at 157.48 156.21 0)
			(effects
				(font
					(size 1.27 1.27)
					(thickness 0.15)
				)
				(justify left bottom)
				(hide yes)
			)
		)
		(property "License" "Apache-2.0"
			(at 157.48 158.75 0)
			(effects
				(font
					(size 1.27 1.27)
					(thickness 0.15)
				)
				(justify left bottom)
				(hide yes)
			)
		)
		(pin "1"
		)
		(instances
			(project "thunderbolt-gpu-adapter"
				(path ""
					(reference "#PWR057")
					(unit 1)
				)
			)
		)
	)
	(symbol
		(lib_id "antmicroCapacitorsmisc:C_22u_1206_35V")
		(at 64.77 337.82 90)
		(unit 1)
		(exclude_from_sim no)
		(in_bom yes)
		(on_board yes)
		(dnp no)
		(fields_autoplaced yes)
		(property "Reference" "C13"
			(at 67.31 334.0036 90)
			(effects
				(font
					(size 1.27 1.27)
					(thickness 0.15)
				)
				(justify right)
			)
		)
		(property "Value" "C_22u_1206_35V"
			(at 74.93 317.5 0)
			(effects
				(font
					(size 1.27 1.27)
					(thickness 0.15)
				)
				(justify left bottom)
				(hide yes)
			)
		)
		(property "Footprint" "antmicro-footprints:C_1206_3216Metric"
			(at 77.47 317.5 0)
			(effects
				(font
					(size 1.27 1.27)
					(thickness 0.15)
				)
				(justify left bottom)
				(hide yes)
			)
		)
		(property "Datasheet" "https://product.tdk.com/en/search/capacitor/ceramic/mlcc/info?part_no=3216X5R1V226M160AC"
			(at 80.01 317.5 0)
			(effects
				(font
					(size 1.27 1.27)
					(thickness 0.15)
				)
				(justify left bottom)
				(hide yes)
			)
		)
		(property "Description" ""
			(at 64.77 337.82 0)
			(effects
				(font
					(size 1.27 1.27)
				)
				(hide yes)
			)
		)
		(property "MPN" "3216X5R1V226M160AC"
			(at 82.55 317.5 0)
			(effects
				(font
					(size 1.27 1.27)
					(thickness 0.15)
				)
				(justify left bottom)
				(hide yes)
			)
		)
		(property "Manufacturer" "TDK"
			(at 85.09 317.5 0)
			(effects
				(font
					(size 1.27 1.27)
					(thickness 0.15)
				)
				(justify left bottom)
				(hide yes)
			)
		)
		(property "License" "Apache-2.0"
			(at 87.63 317.5 0)
			(effects
				(font
					(size 1.27 1.27)
					(thickness 0.15)
				)
				(justify left bottom)
				(hide yes)
			)
		)
		(property "Val" "22u"
			(at 67.31 336.5436 90)
			(effects
				(font
					(size 1.27 1.27)
					(thickness 0.15)
				)
				(justify right)
			)
		)
		(property "Voltage" "35V"
			(at 92.71 317.5 0)
			(effects
				(font
					(size 1.27 1.27)
				)
				(justify left bottom)
				(hide yes)
			)
		)
		(property "Dielectric" ""
			(at 95.25 317.5 0)
			(effects
				(font
					(size 1.27 1.27)
				)
				(justify left bottom)
				(hide yes)
			)
		)
		(property "Author" "Antmicro"
			(at 90.17 317.5 0)
			(effects
				(font
					(size 1.27 1.27)
					(thickness 0.15)
				)
				(justify left bottom)
				(hide yes)
			)
		)
		(pin "1"
		)
		(pin "2"
		)
		(instances
			(project "thunderbolt-gpu-adapter"
				(path ""
					(reference "C13")
					(unit 1)
				)
			)
		)
	)
	(symbol
		(lib_id "antmicroResistors0402:R_2k2_0402")
		(at 223.52 325.12 270)
		(mirror x)
		(unit 1)
		(exclude_from_sim no)
		(in_bom yes)
		(on_board yes)
		(dnp no)
		(property "Reference" "R46"
			(at 220.98 321.31 90)
			(effects
				(font
					(size 1.27 1.27)
					(thickness 0.15)
				)
				(justify right)
			)
		)
		(property "Value" "R_2k2_0402"
			(at 210.82 304.8 0)
			(effects
				(font
					(size 1.27 1.27)
					(thickness 0.15)
				)
				(justify left bottom)
				(hide yes)
			)
		)
		(property "Footprint" "antmicro-footprints:R_0402_1005Metric"
			(at 208.28 304.8 0)
			(effects
				(font
					(size 1.27 1.27)
					(thickness 0.15)
				)
				(justify left bottom)
				(hide yes)
			)
		)
		(property "Datasheet" "https://www.bourns.com/docs/product-datasheets/cr.pdf"
			(at 205.74 304.8 0)
			(effects
				(font
					(size 1.27 1.27)
					(thickness 0.15)
				)
				(justify left bottom)
				(hide yes)
			)
		)
		(property "Description" ""
			(at 223.52 325.12 0)
			(effects
				(font
					(size 1.27 1.27)
				)
				(hide yes)
			)
		)
		(property "MPN" "CR0402-FX-2201GLF"
			(at 203.2 304.8 0)
			(effects
				(font
					(size 1.27 1.27)
					(thickness 0.15)
				)
				(justify left bottom)
				(hide yes)
			)
		)
		(property "Manufacturer" "Bourns"
			(at 200.66 304.8 0)
			(effects
				(font
					(size 1.27 1.27)
					(thickness 0.15)
				)
				(justify left bottom)
				(hide yes)
			)
		)
		(property "License" "Apache-2.0"
			(at 198.12 304.8 0)
			(effects
				(font
					(size 1.27 1.27)
					(thickness 0.15)
				)
				(justify left bottom)
				(hide yes)
			)
		)
		(property "Val" "2k2"
			(at 220.98 323.85 90)
			(effects
				(font
					(size 1.27 1.27)
					(thickness 0.15)
				)
				(justify right)
			)
		)
		(property "Tolerance" "1%"
			(at 213.36 304.8 0)
			(effects
				(font
					(size 1.27 1.27)
				)
				(justify left bottom)
				(hide yes)
			)
		)
		(property "Author" "Antmicro"
			(at 195.58 304.8 0)
			(effects
				(font
					(size 1.27 1.27)
					(thickness 0.15)
				)
				(justify left bottom)
				(hide yes)
			)
		)
		(pin "1"
		)
		(pin "2"
		)
		(instances
			(project "thunderbolt-gpu-adapter"
				(path ""
					(reference "R46")
					(unit 1)
				)
			)
		)
	)
	(symbol
		(lib_id "antmicroResistors0402:R_0R_0402")
		(at 135.89 133.35 0)
		(unit 1)
		(exclude_from_sim no)
		(in_bom yes)
		(on_board yes)
		(dnp no)
		(property "Reference" "R31"
			(at 138.43 131.445 0)
			(effects
				(font
					(size 1.27 1.27)
					(thickness 0.15)
				)
			)
		)
		(property "Value" "R_0R_0402"
			(at 156.21 146.05 0)
			(effects
				(font
					(size 1.27 1.27)
					(thickness 0.15)
				)
				(justify left bottom)
				(hide yes)
			)
		)
		(property "Footprint" "antmicro-footprints:R_0402_1005Metric"
			(at 156.21 148.59 0)
			(effects
				(font
					(size 1.27 1.27)
					(thickness 0.15)
				)
				(justify left bottom)
				(hide yes)
			)
		)
		(property "Datasheet" "https://industrial.panasonic.com/cdbs/www-data/pdf/RDA0000/AOA0000C301.pdf"
			(at 156.21 151.13 0)
			(effects
				(font
					(size 1.27 1.27)
					(thickness 0.15)
				)
				(justify left bottom)
				(hide yes)
			)
		)
		(property "Description" ""
			(at 135.89 133.35 0)
			(effects
				(font
					(size 1.27 1.27)
				)
				(hide yes)
			)
		)
		(property "MPN" "ERJ2GE0R00X"
			(at 156.21 153.67 0)
			(effects
				(font
					(size 1.27 1.27)
					(thickness 0.15)
				)
				(justify left bottom)
				(hide yes)
			)
		)
		(property "Manufacturer" "Panasonic"
			(at 156.21 156.21 0)
			(effects
				(font
					(size 1.27 1.27)
					(thickness 0.15)
				)
				(justify left bottom)
				(hide yes)
			)
		)
		(property "License" "Apache-2.0"
			(at 156.21 158.75 0)
			(effects
				(font
					(size 1.27 1.27)
					(thickness 0.15)
				)
				(justify left bottom)
				(hide yes)
			)
		)
		(property "Val" "0R"
			(at 138.43 133.35 0)
			(effects
				(font
					(size 1.27 1.27)
					(thickness 0.15)
				)
			)
		)
		(property "Tolerance" "~"
			(at 156.21 143.51 0)
			(effects
				(font
					(size 1.27 1.27)
				)
				(justify left bottom)
				(hide yes)
			)
		)
		(property "Current" "1A"
			(at 138.43 130.175 0)
			(effects
				(font
					(size 1.27 1.27)
					(thickness 0.15)
				)
				(hide yes)
			)
		)
		(property "Author" "Antmicro"
			(at 156.21 161.29 0)
			(effects
				(font
					(size 1.27 1.27)
					(thickness 0.15)
				)
				(justify left bottom)
				(hide yes)
			)
		)
		(pin "1"
		)
		(pin "2"
		)
		(instances
			(project "thunderbolt-gpu-adapter"
				(path ""
					(reference "R31")
					(unit 1)
				)
			)
		)
	)
	(symbol
		(lib_id "antmicropower:GND")
		(at 52.07 394.97 0)
		(unit 1)
		(exclude_from_sim no)
		(in_bom yes)
		(on_board yes)
		(dnp no)
		(property "Reference" "#PWR0192"
			(at 52.07 401.32 0)
			(effects
				(font
					(size 1.27 1.27)
				)
				(hide yes)
			)
		)
		(property "Value" "GND"
			(at 52.07 398.78 0)
			(effects
				(font
					(size 1.27 1.27)
				)
			)
		)
		(property "Footprint" ""
			(at 52.07 394.97 0)
			(effects
				(font
					(size 1.27 1.27)
				)
				(hide yes)
			)
		)
		(property "Datasheet" ""
			(at 52.07 394.97 0)
			(effects
				(font
					(size 1.27 1.27)
				)
				(hide yes)
			)
		)
		(property "Description" ""
			(at 52.07 394.97 0)
			(effects
				(font
					(size 1.27 1.27)
				)
				(hide yes)
			)
		)
		(property "Author" "Antmicro"
			(at 60.96 402.59 0)
			(effects
				(font
					(size 1.27 1.27)
					(thickness 0.15)
				)
				(justify left bottom)
				(hide yes)
			)
		)
		(property "License" "Apache-2.0"
			(at 60.96 405.13 0)
			(effects
				(font
					(size 1.27 1.27)
					(thickness 0.15)
				)
				(justify left bottom)
				(hide yes)
			)
		)
		(pin "1"
		)
		(instances
			(project "thunderbolt-gpu-adapter"
				(path ""
					(reference "#PWR0192")
					(unit 1)
				)
			)
		)
	)
	(symbol
		(lib_id "antmicroResistors0402:R_100k_0402")
		(at 135.89 125.73 0)
		(unit 1)
		(exclude_from_sim no)
		(in_bom yes)
		(on_board yes)
		(dnp no)
		(property "Reference" "R29"
			(at 133.985 124.46 0)
			(effects
				(font
					(size 1.27 1.27)
					(thickness 0.15)
				)
			)
		)
		(property "Value" "R_100k_0402"
			(at 156.21 138.43 0)
			(effects
				(font
					(size 1.27 1.27)
					(thickness 0.15)
				)
				(justify left bottom)
				(hide yes)
			)
		)
		(property "Footprint" "antmicro-footprints:R_0402_1005Metric"
			(at 156.21 140.97 0)
			(effects
				(font
					(size 1.27 1.27)
					(thickness 0.15)
				)
				(justify left bottom)
				(hide yes)
			)
		)
		(property "Datasheet" "https://www.bourns.com/docs/product-datasheets/cr.pdf"
			(at 156.21 143.51 0)
			(effects
				(font
					(size 1.27 1.27)
					(thickness 0.15)
				)
				(justify left bottom)
				(hide yes)
			)
		)
		(property "Description" ""
			(at 135.89 125.73 0)
			(effects
				(font
					(size 1.27 1.27)
				)
				(hide yes)
			)
		)
		(property "MPN" "CR0402-FX-1003GLF"
			(at 156.21 146.05 0)
			(effects
				(font
					(size 1.27 1.27)
					(thickness 0.15)
				)
				(justify left bottom)
				(hide yes)
			)
		)
		(property "Manufacturer" "Bourns"
			(at 156.21 148.59 0)
			(effects
				(font
					(size 1.27 1.27)
					(thickness 0.15)
				)
				(justify left bottom)
				(hide yes)
			)
		)
		(property "License" "Apache-2.0"
			(at 156.21 151.13 0)
			(effects
				(font
					(size 1.27 1.27)
					(thickness 0.15)
				)
				(justify left bottom)
				(hide yes)
			)
		)
		(property "Val" "100k"
			(at 142.875 124.46 0)
			(effects
				(font
					(size 1.27 1.27)
					(thickness 0.15)
				)
			)
		)
		(property "Tolerance" "1%"
			(at 156.21 135.89 0)
			(effects
				(font
					(size 1.27 1.27)
				)
				(justify left bottom)
				(hide yes)
			)
		)
		(property "Author" "Antmicro"
			(at 156.21 153.67 0)
			(effects
				(font
					(size 1.27 1.27)
					(thickness 0.15)
				)
				(justify left bottom)
				(hide yes)
			)
		)
		(pin "1"
		)
		(pin "2"
		)
		(instances
			(project "thunderbolt-gpu-adapter"
				(path ""
					(reference "R29")
					(unit 1)
				)
			)
		)
	)
	(symbol
		(lib_id "antmicroCapacitorsmisc:C_10u_0805_35V")
		(at 29.21 205.74 90)
		(unit 1)
		(exclude_from_sim no)
		(in_bom yes)
		(on_board yes)
		(dnp no)
		(property "Reference" "C7"
			(at 22.86 201.295 90)
			(effects
				(font
					(size 1.27 1.27)
					(thickness 0.15)
				)
				(justify right)
			)
		)
		(property "Value" "C_10u_0805_35V"
			(at 39.37 185.42 0)
			(effects
				(font
					(size 1.27 1.27)
					(thickness 0.15)
				)
				(justify left bottom)
				(hide yes)
			)
		)
		(property "Footprint" "antmicro-footprints:C_0805_2012Metric"
			(at 41.91 185.42 0)
			(effects
				(font
					(size 1.27 1.27)
					(thickness 0.15)
				)
				(justify left bottom)
				(hide yes)
			)
		)
		(property "Datasheet" "https://www.murata.com/products/productdetail?partno=GRM21BR6YA106KE43%23"
			(at 44.45 185.42 0)
			(effects
				(font
					(size 1.27 1.27)
					(thickness 0.15)
				)
				(justify left bottom)
				(hide yes)
			)
		)
		(property "Description" ""
			(at 29.21 205.74 0)
			(effects
				(font
					(size 1.27 1.27)
				)
				(hide yes)
			)
		)
		(property "MPN" "GRM21BR6YA106KE43L"
			(at 46.99 185.42 0)
			(effects
				(font
					(size 1.27 1.27)
					(thickness 0.15)
				)
				(justify left bottom)
				(hide yes)
			)
		)
		(property "Manufacturer" "Murata"
			(at 49.53 185.42 0)
			(effects
				(font
					(size 1.27 1.27)
					(thickness 0.15)
				)
				(justify left bottom)
				(hide yes)
			)
		)
		(property "License" "Apache-2.0"
			(at 52.07 185.42 0)
			(effects
				(font
					(size 1.27 1.27)
					(thickness 0.15)
				)
				(justify left bottom)
				(hide yes)
			)
		)
		(property "Val" "10u"
			(at 26.67 202.565 90)
			(effects
				(font
					(size 1.27 1.27)
					(thickness 0.15)
				)
				(justify left bottom)
			)
		)
		(property "Voltage" "35V"
			(at 57.15 185.42 0)
			(effects
				(font
					(size 1.27 1.27)
				)
				(justify left bottom)
				(hide yes)
			)
		)
		(property "Dielectric" ""
			(at 59.69 185.42 0)
			(effects
				(font
					(size 1.27 1.27)
				)
				(justify left bottom)
				(hide yes)
			)
		)
		(property "Author" "Antmicro"
			(at 54.61 185.42 0)
			(effects
				(font
					(size 1.27 1.27)
					(thickness 0.15)
				)
				(justify left bottom)
				(hide yes)
			)
		)
		(pin "1"
		)
		(pin "2"
		)
		(instances
			(project "thunderbolt-gpu-adapter"
				(path ""
					(reference "C7")
					(unit 1)
				)
			)
		)
	)
	(symbol
		(lib_id "antmicroCapacitors0402:C_2u2_0402")
		(at 133.35 64.77 0)
		(unit 1)
		(exclude_from_sim no)
		(in_bom yes)
		(on_board yes)
		(dnp no)
		(property "Reference" "C36"
			(at 138.43 63.5 0)
			(effects
				(font
					(size 1.27 1.27)
					(thickness 0.15)
				)
			)
		)
		(property "Value" "C_2u2_0402"
			(at 153.67 74.93 0)
			(effects
				(font
					(size 1.27 1.27)
					(thickness 0.15)
				)
				(justify left bottom)
				(hide yes)
			)
		)
		(property "Footprint" "antmicro-footprints:C_0402_1005Metric"
			(at 153.67 77.47 0)
			(effects
				(font
					(size 1.27 1.27)
					(thickness 0.15)
				)
				(justify left bottom)
				(hide yes)
			)
		)
		(property "Datasheet" "https://product.tdk.com/en/search/capacitor/ceramic/mlcc/info?part_no=C1005X5R1A225K050BC"
			(at 153.67 80.01 0)
			(effects
				(font
					(size 1.27 1.27)
					(thickness 0.15)
				)
				(justify left bottom)
				(hide yes)
			)
		)
		(property "Description" ""
			(at 133.35 64.77 0)
			(effects
				(font
					(size 1.27 1.27)
				)
				(hide yes)
			)
		)
		(property "MPN" "C1005X5R1A225K050BC"
			(at 153.67 82.55 0)
			(effects
				(font
					(size 1.27 1.27)
					(thickness 0.15)
				)
				(justify left bottom)
				(hide yes)
			)
		)
		(property "Manufacturer" "TDK"
			(at 153.67 85.09 0)
			(effects
				(font
					(size 1.27 1.27)
					(thickness 0.15)
				)
				(justify left bottom)
				(hide yes)
			)
		)
		(property "License" "Apache-2.0"
			(at 153.67 87.63 0)
			(effects
				(font
					(size 1.27 1.27)
					(thickness 0.15)
				)
				(justify left bottom)
				(hide yes)
			)
		)
		(property "Val" "2u2"
			(at 138.43 66.04 0)
			(effects
				(font
					(size 1.27 1.27)
					(thickness 0.15)
				)
			)
		)
		(property "Voltage" ""
			(at 153.67 92.71 0)
			(effects
				(font
					(size 1.27 1.27)
				)
				(justify left bottom)
				(hide yes)
			)
		)
		(property "Dielectric" ""
			(at 153.67 95.25 0)
			(effects
				(font
					(size 1.27 1.27)
				)
				(justify left bottom)
				(hide yes)
			)
		)
		(property "Author" "Antmicro"
			(at 153.67 90.17 0)
			(effects
				(font
					(size 1.27 1.27)
					(thickness 0.15)
				)
				(justify left bottom)
				(hide yes)
			)
		)
		(pin "1"
		)
		(pin "2"
		)
		(instances
			(project "thunderbolt-gpu-adapter"
				(path ""
					(reference "C36")
					(unit 1)
				)
			)
		)
	)
	(symbol
		(lib_id "antmicropower:GND")
		(at 72.39 171.45 0)
		(unit 1)
		(exclude_from_sim no)
		(in_bom yes)
		(on_board yes)
		(dnp no)
		(property "Reference" "#PWR040"
			(at 72.39 177.8 0)
			(effects
				(font
					(size 1.27 1.27)
				)
				(hide yes)
			)
		)
		(property "Value" "GND"
			(at 72.39 175.26 0)
			(effects
				(font
					(size 1.27 1.27)
				)
			)
		)
		(property "Footprint" ""
			(at 72.39 171.45 0)
			(effects
				(font
					(size 1.27 1.27)
				)
				(hide yes)
			)
		)
		(property "Datasheet" ""
			(at 72.39 171.45 0)
			(effects
				(font
					(size 1.27 1.27)
				)
				(hide yes)
			)
		)
		(property "Description" ""
			(at 72.39 171.45 0)
			(effects
				(font
					(size 1.27 1.27)
				)
				(hide yes)
			)
		)
		(property "Author" "Antmicro"
			(at 81.28 179.07 0)
			(effects
				(font
					(size 1.27 1.27)
					(thickness 0.15)
				)
				(justify left bottom)
				(hide yes)
			)
		)
		(property "License" "Apache-2.0"
			(at 81.28 181.61 0)
			(effects
				(font
					(size 1.27 1.27)
					(thickness 0.15)
				)
				(justify left bottom)
				(hide yes)
			)
		)
		(pin "1"
		)
		(instances
			(project "thunderbolt-gpu-adapter"
				(path ""
					(reference "#PWR040")
					(unit 1)
				)
			)
		)
	)
	(symbol
		(lib_id "antmicropower:GND")
		(at 173.99 58.42 0)
		(unit 1)
		(exclude_from_sim no)
		(in_bom yes)
		(on_board yes)
		(dnp no)
		(property "Reference" "#PWR063"
			(at 173.99 64.77 0)
			(effects
				(font
					(size 1.27 1.27)
				)
				(hide yes)
			)
		)
		(property "Value" "GND"
			(at 173.99 62.23 0)
			(effects
				(font
					(size 1.27 1.27)
				)
			)
		)
		(property "Footprint" ""
			(at 173.99 58.42 0)
			(effects
				(font
					(size 1.27 1.27)
				)
				(hide yes)
			)
		)
		(property "Datasheet" ""
			(at 173.99 58.42 0)
			(effects
				(font
					(size 1.27 1.27)
				)
				(hide yes)
			)
		)
		(property "Description" ""
			(at 173.99 58.42 0)
			(effects
				(font
					(size 1.27 1.27)
				)
				(hide yes)
			)
		)
		(property "Author" "Antmicro"
			(at 182.88 66.04 0)
			(effects
				(font
					(size 1.27 1.27)
					(thickness 0.15)
				)
				(justify left bottom)
				(hide yes)
			)
		)
		(property "License" "Apache-2.0"
			(at 182.88 68.58 0)
			(effects
				(font
					(size 1.27 1.27)
					(thickness 0.15)
				)
				(justify left bottom)
				(hide yes)
			)
		)
		(pin "1"
		)
		(instances
			(project "thunderbolt-gpu-adapter"
				(path ""
					(reference "#PWR063")
					(unit 1)
				)
			)
		)
	)
	(symbol
		(lib_id "antmicroCapacitors0402:C_100n_0402")
		(at 153.67 55.88 90)
		(unit 1)
		(exclude_from_sim no)
		(in_bom yes)
		(on_board yes)
		(dnp no)
		(fields_autoplaced yes)
		(property "Reference" "C150"
			(at 156.21 52.0636 90)
			(effects
				(font
					(size 1.27 1.27)
					(thickness 0.15)
				)
				(justify right)
			)
		)
		(property "Value" "C_100n_0402"
			(at 163.83 35.56 0)
			(effects
				(font
					(size 1.27 1.27)
					(thickness 0.15)
				)
				(justify left bottom)
				(hide yes)
			)
		)
		(property "Footprint" "antmicro-footprints:C_0402_1005Metric"
			(at 166.37 35.56 0)
			(effects
				(font
					(size 1.27 1.27)
					(thickness 0.15)
				)
				(justify left bottom)
				(hide yes)
			)
		)
		(property "Datasheet" "https://www.murata.com/products/productdetail?partno=GRM155R61H104KE14%23"
			(at 168.91 35.56 0)
			(effects
				(font
					(size 1.27 1.27)
					(thickness 0.15)
				)
				(justify left bottom)
				(hide yes)
			)
		)
		(property "Description" ""
			(at 153.67 55.88 0)
			(effects
				(font
					(size 1.27 1.27)
				)
				(hide yes)
			)
		)
		(property "MPN" "GRM155R61H104KE14D"
			(at 171.45 35.56 0)
			(effects
				(font
					(size 1.27 1.27)
					(thickness 0.15)
				)
				(justify left bottom)
				(hide yes)
			)
		)
		(property "Manufacturer" "Murata"
			(at 173.99 35.56 0)
			(effects
				(font
					(size 1.27 1.27)
					(thickness 0.15)
				)
				(justify left bottom)
				(hide yes)
			)
		)
		(property "License" "Apache-2.0"
			(at 176.53 35.56 0)
			(effects
				(font
					(size 1.27 1.27)
					(thickness 0.15)
				)
				(justify left bottom)
				(hide yes)
			)
		)
		(property "Author" "Antmicro"
			(at 179.07 35.56 0)
			(effects
				(font
					(size 1.27 1.27)
					(thickness 0.15)
				)
				(justify left bottom)
				(hide yes)
			)
		)
		(property "Val" "100n"
			(at 156.21 54.6036 90)
			(effects
				(font
					(size 1.27 1.27)
					(thickness 0.15)
				)
				(justify right)
			)
		)
		(property "Voltage" "50V"
			(at 181.61 35.56 0)
			(effects
				(font
					(size 1.27 1.27)
				)
				(justify left bottom)
				(hide yes)
			)
		)
		(property "Dielectric" "X5R"
			(at 184.15 35.56 0)
			(effects
				(font
					(size 1.27 1.27)
				)
				(justify left bottom)
				(hide yes)
			)
		)
		(pin "1"
		)
		(pin "2"
		)
		(instances
			(project "thunderbolt-gpu-adapter"
				(path ""
					(reference "C150")
					(unit 1)
				)
			)
		)
	)
	(symbol
		(lib_id "antmicroCapacitors0402:C_1u_0402")
		(at 111.76 208.28 0)
		(mirror x)
		(unit 1)
		(exclude_from_sim no)
		(in_bom yes)
		(on_board yes)
		(dnp no)
		(property "Reference" "C18"
			(at 111.76 207.01 0)
			(effects
				(font
					(size 1.27 1.27)
					(thickness 0.15)
				)
			)
		)
		(property "Value" "C_1u_0402"
			(at 132.08 198.12 0)
			(effects
				(font
					(size 1.27 1.27)
					(thickness 0.15)
				)
				(justify left bottom)
				(hide yes)
			)
		)
		(property "Footprint" "antmicro-footprints:C_0402_1005Metric"
			(at 132.08 195.58 0)
			(effects
				(font
					(size 1.27 1.27)
					(thickness 0.15)
				)
				(justify left bottom)
				(hide yes)
			)
		)
		(property "Datasheet" "https://product.tdk.com/en/search/capacitor/ceramic/mlcc/info?part_no=C1005X6S1A105K050BC"
			(at 132.08 193.04 0)
			(effects
				(font
					(size 1.27 1.27)
					(thickness 0.15)
				)
				(justify left bottom)
				(hide yes)
			)
		)
		(property "Description" ""
			(at 111.76 208.28 0)
			(effects
				(font
					(size 1.27 1.27)
				)
				(hide yes)
			)
		)
		(property "MPN" "C1005X6S1A105K050BC"
			(at 132.08 190.5 0)
			(effects
				(font
					(size 1.27 1.27)
					(thickness 0.15)
				)
				(justify left bottom)
				(hide yes)
			)
		)
		(property "Manufacturer" "TDK"
			(at 132.08 187.96 0)
			(effects
				(font
					(size 1.27 1.27)
					(thickness 0.15)
				)
				(justify left bottom)
				(hide yes)
			)
		)
		(property "License" "Apache-2.0"
			(at 132.08 185.42 0)
			(effects
				(font
					(size 1.27 1.27)
					(thickness 0.15)
				)
				(justify left bottom)
				(hide yes)
			)
		)
		(property "Val" "1u"
			(at 116.84 207.01 0)
			(effects
				(font
					(size 1.27 1.27)
					(thickness 0.15)
				)
			)
		)
		(property "Voltage" ""
			(at 132.08 180.34 0)
			(effects
				(font
					(size 1.27 1.27)
				)
				(justify left bottom)
				(hide yes)
			)
		)
		(property "Dielectric" ""
			(at 132.08 177.8 0)
			(effects
				(font
					(size 1.27 1.27)
				)
				(justify left bottom)
				(hide yes)
			)
		)
		(property "Author" "Antmicro"
			(at 132.08 182.88 0)
			(effects
				(font
					(size 1.27 1.27)
					(thickness 0.15)
				)
				(justify left bottom)
				(hide yes)
			)
		)
		(pin "1"
		)
		(pin "2"
		)
		(instances
			(project "thunderbolt-gpu-adapter"
				(path ""
					(reference "C18")
					(unit 1)
				)
			)
		)
	)
	(symbol
		(lib_id "antmicroCapacitors0603:C_22u_0603")
		(at 172.72 358.14 90)
		(unit 1)
		(exclude_from_sim no)
		(in_bom yes)
		(on_board yes)
		(dnp no)
		(fields_autoplaced yes)
		(property "Reference" "C41"
			(at 175.26 354.3236 90)
			(effects
				(font
					(size 1.27 1.27)
					(thickness 0.15)
				)
				(justify right)
			)
		)
		(property "Value" "C_22u_0603"
			(at 182.88 337.82 0)
			(effects
				(font
					(size 1.27 1.27)
					(thickness 0.15)
				)
				(justify left bottom)
				(hide yes)
			)
		)
		(property "Footprint" "antmicro-footprints:C_0603_1608Metric"
			(at 185.42 337.82 0)
			(effects
				(font
					(size 1.27 1.27)
					(thickness 0.15)
				)
				(justify left bottom)
				(hide yes)
			)
		)
		(property "Datasheet" "https://www.murata.com/products/productdetail?partno=GRM188R60J226MEA0%23"
			(at 187.96 337.82 0)
			(effects
				(font
					(size 1.27 1.27)
					(thickness 0.15)
				)
				(justify left bottom)
				(hide yes)
			)
		)
		(property "Description" ""
			(at 172.72 358.14 0)
			(effects
				(font
					(size 1.27 1.27)
				)
				(hide yes)
			)
		)
		(property "MPN" "GRM188R60J226MEA0D"
			(at 190.5 337.82 0)
			(effects
				(font
					(size 1.27 1.27)
					(thickness 0.15)
				)
				(justify left bottom)
				(hide yes)
			)
		)
		(property "Manufacturer" "Murata"
			(at 193.04 337.82 0)
			(effects
				(font
					(size 1.27 1.27)
					(thickness 0.15)
				)
				(justify left bottom)
				(hide yes)
			)
		)
		(property "License" "Apache-2.0"
			(at 195.58 337.82 0)
			(effects
				(font
					(size 1.27 1.27)
					(thickness 0.15)
				)
				(justify left bottom)
				(hide yes)
			)
		)
		(property "Val" "22u"
			(at 175.26 356.8636 90)
			(effects
				(font
					(size 1.27 1.27)
					(thickness 0.15)
				)
				(justify right)
			)
		)
		(property "Voltage" ""
			(at 200.66 337.82 0)
			(effects
				(font
					(size 1.27 1.27)
				)
				(justify left bottom)
				(hide yes)
			)
		)
		(property "Dielectric" ""
			(at 203.2 337.82 0)
			(effects
				(font
					(size 1.27 1.27)
				)
				(justify left bottom)
				(hide yes)
			)
		)
		(property "Author" "Antmicro"
			(at 198.12 337.82 0)
			(effects
				(font
					(size 1.27 1.27)
					(thickness 0.15)
				)
				(justify left bottom)
				(hide yes)
			)
		)
		(pin "1"
		)
		(pin "2"
		)
		(instances
			(project "thunderbolt-gpu-adapter"
				(path ""
					(reference "C41")
					(unit 1)
				)
			)
		)
	)
	(symbol
		(lib_id "antmicroCapacitorspol:C_Pol_330u_16V_KYOCERA-AVX-TCJ-E")
		(at 213.36 275.59 90)
		(mirror x)
		(unit 1)
		(exclude_from_sim no)
		(in_bom yes)
		(on_board yes)
		(dnp no)
		(property "Reference" "C130"
			(at 210.82 276.3266 90)
			(effects
				(font
					(size 1.27 1.27)
					(thickness 0.15)
				)
				(justify left)
			)
		)
		(property "Value" "C_Pol_330u_16V_KYOCERA-AVX-TCJ-E"
			(at 215.9 289.56 0)
			(effects
				(font
					(size 1.27 1.27)
					(thickness 0.15)
				)
				(justify left bottom)
				(hide yes)
			)
		)
		(property "Footprint" "antmicro-footprints:C_Pol_EIA-E"
			(at 220.98 289.56 0)
			(effects
				(font
					(size 1.27 1.27)
					(thickness 0.15)
				)
				(justify left bottom)
				(hide yes)
			)
		)
		(property "Datasheet" "https://spicat.kyocera-avx.com/product/tan/chartview/TCJE337M016R0070E/"
			(at 223.52 289.56 0)
			(effects
				(font
					(size 1.27 1.27)
					(thickness 0.15)
				)
				(justify left bottom)
				(hide yes)
			)
		)
		(property "Description" ""
			(at 213.36 275.59 0)
			(effects
				(font
					(size 1.27 1.27)
				)
				(hide yes)
			)
		)
		(property "Val" "330u"
			(at 210.82 278.8666 90)
			(effects
				(font
					(size 1.27 1.27)
					(thickness 0.15)
				)
				(justify left)
			)
		)
		(property "MPN" "TCJE337M016R0070E"
			(at 226.06 289.56 0)
			(effects
				(font
					(size 1.27 1.27)
					(thickness 0.15)
				)
				(justify left bottom)
				(hide yes)
			)
		)
		(property "Manufacturer" "KYOCERA AVX"
			(at 228.6 289.56 0)
			(effects
				(font
					(size 1.27 1.27)
					(thickness 0.15)
				)
				(justify left bottom)
				(hide yes)
			)
		)
		(property "License" "Apache-2.0"
			(at 231.14 289.56 0)
			(effects
				(font
					(size 1.27 1.27)
					(thickness 0.15)
				)
				(justify left bottom)
				(hide yes)
			)
		)
		(property "Author" "Antmicro"
			(at 233.68 289.56 0)
			(effects
				(font
					(size 1.27 1.27)
					(thickness 0.15)
				)
				(justify left bottom)
				(hide yes)
			)
		)
		(property "Voltage" "16V"
			(at 236.22 289.56 0)
			(effects
				(font
					(size 1.27 1.27)
				)
				(justify left bottom)
				(hide yes)
			)
		)
		(property "Dielectric" "template_dielectric"
			(at 238.76 289.56 0)
			(effects
				(font
					(size 1.27 1.27)
				)
				(justify left bottom)
				(hide yes)
			)
		)
		(pin "1"
		)
		(pin "2"
		)
		(instances
			(project "thunderbolt-gpu-adapter"
				(path ""
					(reference "C130")
					(unit 1)
				)
			)
		)
	)
	(symbol
		(lib_id "antmicroTestPoints:TP_1mm_SMD")
		(at 74.93 328.93 90)
		(unit 1)
		(exclude_from_sim no)
		(in_bom no)
		(on_board yes)
		(dnp no)
		(property "Reference" "TP2"
			(at 73.025 323.85 90)
			(effects
				(font
					(size 1.27 1.27)
					(thickness 0.15)
				)
				(justify right)
			)
		)
		(property "Value" "TP_1mm_SMD"
			(at 76.835 325.7549 90)
			(effects
				(font
					(size 1.27 1.27)
					(thickness 0.15)
				)
				(justify right)
				(hide yes)
			)
		)
		(property "Footprint" "antmicro-footprints:TP_SMD_1mm"
			(at 85.09 313.69 0)
			(effects
				(font
					(size 1.27 1.27)
					(thickness 0.15)
				)
				(justify left bottom)
				(hide yes)
			)
		)
		(property "Datasheet" ""
			(at 87.63 313.69 0)
			(effects
				(font
					(size 1.27 1.27)
					(thickness 0.15)
				)
				(justify left bottom)
				(hide yes)
			)
		)
		(property "Description" ""
			(at 74.93 328.93 0)
			(effects
				(font
					(size 1.27 1.27)
				)
				(hide yes)
			)
		)
		(property "License" "Apache-2.0"
			(at 92.71 313.69 0)
			(effects
				(font
					(size 1.27 1.27)
					(thickness 0.15)
				)
				(justify left bottom)
				(hide yes)
			)
		)
		(property "Manufacturer" ""
			(at 76.835 328.2949 90)
			(effects
				(font
					(size 1.27 1.27)
				)
				(justify right)
				(hide yes)
			)
		)
		(property "MPN" ""
			(at 74.93 328.93 0)
			(effects
				(font
					(size 1.27 1.27)
				)
				(hide yes)
			)
		)
		(property "Author" "Antmicro"
			(at 90.17 313.69 0)
			(effects
				(font
					(size 1.27 1.27)
					(thickness 0.15)
				)
				(justify left bottom)
				(hide yes)
			)
		)
		(pin "1"
		)
		(instances
			(project "thunderbolt-gpu-adapter"
				(path ""
					(reference "TP2")
					(unit 1)
				)
			)
		)
	)
	(symbol
		(lib_id "antmicroCapacitors0402:C_1u_0402")
		(at 64.77 62.23 0)
		(unit 1)
		(exclude_from_sim no)
		(in_bom yes)
		(on_board yes)
		(dnp no)
		(property "Reference" "C22"
			(at 64.77 63.5 0)
			(effects
				(font
					(size 1.27 1.27)
					(thickness 0.15)
				)
			)
		)
		(property "Value" "C_1u_0402"
			(at 85.09 72.39 0)
			(effects
				(font
					(size 1.27 1.27)
					(thickness 0.15)
				)
				(justify left bottom)
				(hide yes)
			)
		)
		(property "Footprint" "antmicro-footprints:C_0402_1005Metric"
			(at 85.09 74.93 0)
			(effects
				(font
					(size 1.27 1.27)
					(thickness 0.15)
				)
				(justify left bottom)
				(hide yes)
			)
		)
		(property "Datasheet" "https://product.tdk.com/en/search/capacitor/ceramic/mlcc/info?part_no=C1005X6S1A105K050BC"
			(at 85.09 77.47 0)
			(effects
				(font
					(size 1.27 1.27)
					(thickness 0.15)
				)
				(justify left bottom)
				(hide yes)
			)
		)
		(property "Description" ""
			(at 64.77 62.23 0)
			(effects
				(font
					(size 1.27 1.27)
				)
				(hide yes)
			)
		)
		(property "MPN" "C1005X6S1A105K050BC"
			(at 85.09 80.01 0)
			(effects
				(font
					(size 1.27 1.27)
					(thickness 0.15)
				)
				(justify left bottom)
				(hide yes)
			)
		)
		(property "Manufacturer" "TDK"
			(at 85.09 82.55 0)
			(effects
				(font
					(size 1.27 1.27)
					(thickness 0.15)
				)
				(justify left bottom)
				(hide yes)
			)
		)
		(property "License" "Apache-2.0"
			(at 85.09 85.09 0)
			(effects
				(font
					(size 1.27 1.27)
					(thickness 0.15)
				)
				(justify left bottom)
				(hide yes)
			)
		)
		(property "Val" "1u"
			(at 69.215 63.5 0)
			(effects
				(font
					(size 1.27 1.27)
					(thickness 0.15)
				)
			)
		)
		(property "Voltage" ""
			(at 85.09 90.17 0)
			(effects
				(font
					(size 1.27 1.27)
				)
				(justify left bottom)
				(hide yes)
			)
		)
		(property "Dielectric" ""
			(at 85.09 92.71 0)
			(effects
				(font
					(size 1.27 1.27)
				)
				(justify left bottom)
				(hide yes)
			)
		)
		(property "Author" "Antmicro"
			(at 85.09 87.63 0)
			(effects
				(font
					(size 1.27 1.27)
					(thickness 0.15)
				)
				(justify left bottom)
				(hide yes)
			)
		)
		(pin "1"
		)
		(pin "2"
		)
		(instances
			(project "thunderbolt-gpu-adapter"
				(path ""
					(reference "C22")
					(unit 1)
				)
			)
		)
	)
	(symbol
		(lib_id "antmicropower:GND")
		(at 204.47 120.65 0)
		(unit 1)
		(exclude_from_sim no)
		(in_bom yes)
		(on_board yes)
		(dnp no)
		(property "Reference" "#PWR0167"
			(at 204.47 127 0)
			(effects
				(font
					(size 1.27 1.27)
				)
				(hide yes)
			)
		)
		(property "Value" "GND"
			(at 204.47 124.46 0)
			(effects
				(font
					(size 1.27 1.27)
				)
			)
		)
		(property "Footprint" ""
			(at 204.47 120.65 0)
			(effects
				(font
					(size 1.27 1.27)
				)
				(hide yes)
			)
		)
		(property "Datasheet" ""
			(at 204.47 120.65 0)
			(effects
				(font
					(size 1.27 1.27)
				)
				(hide yes)
			)
		)
		(property "Description" ""
			(at 204.47 120.65 0)
			(effects
				(font
					(size 1.27 1.27)
				)
				(hide yes)
			)
		)
		(property "Author" "Antmicro"
			(at 213.36 128.27 0)
			(effects
				(font
					(size 1.27 1.27)
					(thickness 0.15)
				)
				(justify left bottom)
				(hide yes)
			)
		)
		(property "License" "Apache-2.0"
			(at 213.36 130.81 0)
			(effects
				(font
					(size 1.27 1.27)
					(thickness 0.15)
				)
				(justify left bottom)
				(hide yes)
			)
		)
		(pin "1"
		)
		(instances
			(project "thunderbolt-gpu-adapter"
				(path ""
					(reference "#PWR0167")
					(unit 1)
				)
			)
		)
	)
	(symbol
		(lib_id "antmicroCapacitors0402:C_100n_0402")
		(at 86.36 204.47 270)
		(mirror x)
		(unit 1)
		(exclude_from_sim no)
		(in_bom yes)
		(on_board yes)
		(dnp no)
		(fields_autoplaced yes)
		(property "Reference" "C14"
			(at 88.9 200.6536 90)
			(effects
				(font
					(size 1.27 1.27)
					(thickness 0.15)
				)
				(justify left)
			)
		)
		(property "Value" "C_100n_0402"
			(at 76.2 184.15 0)
			(effects
				(font
					(size 1.27 1.27)
					(thickness 0.15)
				)
				(justify left bottom)
				(hide yes)
			)
		)
		(property "Footprint" "antmicro-footprints:C_0402_1005Metric"
			(at 73.66 184.15 0)
			(effects
				(font
					(size 1.27 1.27)
					(thickness 0.15)
				)
				(justify left bottom)
				(hide yes)
			)
		)
		(property "Datasheet" "https://www.murata.com/products/productdetail?partno=GRM155R61H104KE14%23"
			(at 71.12 184.15 0)
			(effects
				(font
					(size 1.27 1.27)
					(thickness 0.15)
				)
				(justify left bottom)
				(hide yes)
			)
		)
		(property "Description" ""
			(at 86.36 204.47 0)
			(effects
				(font
					(size 1.27 1.27)
				)
				(hide yes)
			)
		)
		(property "MPN" "GRM155R61H104KE14D"
			(at 68.58 184.15 0)
			(effects
				(font
					(size 1.27 1.27)
					(thickness 0.15)
				)
				(justify left bottom)
				(hide yes)
			)
		)
		(property "Manufacturer" "Murata"
			(at 66.04 184.15 0)
			(effects
				(font
					(size 1.27 1.27)
					(thickness 0.15)
				)
				(justify left bottom)
				(hide yes)
			)
		)
		(property "License" "Apache-2.0"
			(at 63.5 184.15 0)
			(effects
				(font
					(size 1.27 1.27)
					(thickness 0.15)
				)
				(justify left bottom)
				(hide yes)
			)
		)
		(property "Val" "100n"
			(at 88.9 203.1936 90)
			(effects
				(font
					(size 1.27 1.27)
					(thickness 0.15)
				)
				(justify left)
			)
		)
		(property "Voltage" "50V"
			(at 58.42 184.15 0)
			(effects
				(font
					(size 1.27 1.27)
				)
				(justify left bottom)
				(hide yes)
			)
		)
		(property "Dielectric" "X5R"
			(at 55.88 184.15 0)
			(effects
				(font
					(size 1.27 1.27)
				)
				(justify left bottom)
				(hide yes)
			)
		)
		(property "Author" "Antmicro"
			(at 60.96 184.15 0)
			(effects
				(font
					(size 1.27 1.27)
					(thickness 0.15)
				)
				(justify left bottom)
				(hide yes)
			)
		)
		(pin "1"
		)
		(pin "2"
		)
		(instances
			(project "thunderbolt-gpu-adapter"
				(path ""
					(reference "C14")
					(unit 1)
				)
			)
		)
	)
	(symbol
		(lib_id "antmicropower:GND")
		(at 25.4 43.18 0)
		(unit 1)
		(exclude_from_sim no)
		(in_bom yes)
		(on_board yes)
		(dnp no)
		(property "Reference" "#PWR0211"
			(at 25.4 49.53 0)
			(effects
				(font
					(size 1.27 1.27)
				)
				(hide yes)
			)
		)
		(property "Value" "GND"
			(at 25.4 46.99 0)
			(effects
				(font
					(size 1.27 1.27)
				)
			)
		)
		(property "Footprint" ""
			(at 25.4 43.18 0)
			(effects
				(font
					(size 1.27 1.27)
				)
				(hide yes)
			)
		)
		(property "Datasheet" ""
			(at 25.4 43.18 0)
			(effects
				(font
					(size 1.27 1.27)
				)
				(hide yes)
			)
		)
		(property "Description" ""
			(at 25.4 43.18 0)
			(effects
				(font
					(size 1.27 1.27)
				)
				(hide yes)
			)
		)
		(property "Author" "Antmicro"
			(at 34.29 50.8 0)
			(effects
				(font
					(size 1.27 1.27)
					(thickness 0.15)
				)
				(justify left bottom)
				(hide yes)
			)
		)
		(property "License" "Apache-2.0"
			(at 34.29 53.34 0)
			(effects
				(font
					(size 1.27 1.27)
					(thickness 0.15)
				)
				(justify left bottom)
				(hide yes)
			)
		)
		(pin "1"
		)
		(instances
			(project "thunderbolt-gpu-adapter"
				(path ""
					(reference "#PWR0211")
					(unit 1)
				)
			)
		)
	)
	(symbol
		(lib_id "antmicroTestPoints:TP_1mm_SMD")
		(at 115.57 215.9 90)
		(unit 1)
		(exclude_from_sim no)
		(in_bom no)
		(on_board yes)
		(dnp no)
		(property "Reference" "TP3"
			(at 116.84 213.36 90)
			(effects
				(font
					(size 1.27 1.27)
					(thickness 0.15)
				)
				(justify right)
			)
		)
		(property "Value" "TP_1mm_SMD"
			(at 123.19 200.66 0)
			(effects
				(font
					(size 1.27 1.27)
					(thickness 0.15)
				)
				(justify left bottom)
				(hide yes)
			)
		)
		(property "Footprint" "antmicro-footprints:TP_SMD_1mm"
			(at 125.73 200.66 0)
			(effects
				(font
					(size 1.27 1.27)
					(thickness 0.15)
				)
				(justify left bottom)
				(hide yes)
			)
		)
		(property "Datasheet" ""
			(at 128.27 198.12 0)
			(effects
				(font
					(size 1.27 1.27)
					(thickness 0.15)
				)
				(justify left bottom)
				(hide yes)
			)
		)
		(property "Description" ""
			(at 115.57 215.9 0)
			(effects
				(font
					(size 1.27 1.27)
				)
				(hide yes)
			)
		)
		(property "License" "Apache-2.0"
			(at 133.35 200.66 0)
			(effects
				(font
					(size 1.27 1.27)
					(thickness 0.15)
				)
				(justify left bottom)
				(hide yes)
			)
		)
		(property "Manufacturer" ""
			(at 115.57 215.9 0)
			(effects
				(font
					(size 1.27 1.27)
				)
				(hide yes)
			)
		)
		(property "MPN" ""
			(at 115.57 215.9 0)
			(effects
				(font
					(size 1.27 1.27)
				)
				(hide yes)
			)
		)
		(property "Author" "Antmicro"
			(at 130.81 200.66 0)
			(effects
				(font
					(size 1.27 1.27)
					(thickness 0.15)
				)
				(justify left bottom)
				(hide yes)
			)
		)
		(pin "1"
		)
		(instances
			(project "thunderbolt-gpu-adapter"
				(path ""
					(reference "TP3")
					(unit 1)
				)
			)
		)
	)
	(symbol
		(lib_id "antmicroResistors0402:R_40k2_0402")
		(at 160.02 353.06 90)
		(unit 1)
		(exclude_from_sim no)
		(in_bom yes)
		(on_board yes)
		(dnp no)
		(fields_autoplaced yes)
		(property "Reference" "R36"
			(at 162.56 349.25 90)
			(effects
				(font
					(size 1.27 1.27)
					(thickness 0.15)
				)
				(justify right)
			)
		)
		(property "Value" "R_40k2_0402"
			(at 172.72 332.74 0)
			(effects
				(font
					(size 1.27 1.27)
					(thickness 0.15)
				)
				(justify left bottom)
				(hide yes)
			)
		)
		(property "Footprint" "antmicro-footprints:R_0402_1005Metric"
			(at 175.26 332.74 0)
			(effects
				(font
					(size 1.27 1.27)
					(thickness 0.15)
				)
				(justify left bottom)
				(hide yes)
			)
		)
		(property "Datasheet" "https://www.bourns.com/docs/product-datasheets/cr.pdf"
			(at 177.8 332.74 0)
			(effects
				(font
					(size 1.27 1.27)
					(thickness 0.15)
				)
				(justify left bottom)
				(hide yes)
			)
		)
		(property "Description" ""
			(at 160.02 353.06 0)
			(effects
				(font
					(size 1.27 1.27)
				)
				(hide yes)
			)
		)
		(property "MPN" "CR0402-FX-4022GLF"
			(at 180.34 332.74 0)
			(effects
				(font
					(size 1.27 1.27)
					(thickness 0.15)
				)
				(justify left bottom)
				(hide yes)
			)
		)
		(property "Manufacturer" "Bourns"
			(at 182.88 332.74 0)
			(effects
				(font
					(size 1.27 1.27)
					(thickness 0.15)
				)
				(justify left bottom)
				(hide yes)
			)
		)
		(property "License" "Apache-2.0"
			(at 185.42 332.74 0)
			(effects
				(font
					(size 1.27 1.27)
					(thickness 0.15)
				)
				(justify left bottom)
				(hide yes)
			)
		)
		(property "Val" "40k2"
			(at 162.56 351.79 90)
			(effects
				(font
					(size 1.27 1.27)
					(thickness 0.15)
				)
				(justify right)
			)
		)
		(property "Tolerance" "1%"
			(at 170.18 332.74 0)
			(effects
				(font
					(size 1.27 1.27)
				)
				(justify left bottom)
				(hide yes)
			)
		)
		(property "Author" "Antmicro"
			(at 187.96 332.74 0)
			(effects
				(font
					(size 1.27 1.27)
					(thickness 0.15)
				)
				(justify left bottom)
				(hide yes)
			)
		)
		(pin "1"
		)
		(pin "2"
		)
		(instances
			(project "thunderbolt-gpu-adapter"
				(path ""
					(reference "R36")
					(unit 1)
				)
			)
		)
	)
	(symbol
		(lib_id "antmicropower:PWR_FLAG")
		(at 182.88 44.45 0)
		(unit 1)
		(exclude_from_sim no)
		(in_bom yes)
		(on_board yes)
		(dnp no)
		(fields_autoplaced yes)
		(property "Reference" "#FLG0107"
			(at 182.88 42.545 0)
			(effects
				(font
					(size 1.27 1.27)
				)
				(hide yes)
			)
		)
		(property "Value" "PWR_FLAG"
			(at 182.88 39.37 0)
			(effects
				(font
					(size 1.27 1.27)
				)
			)
		)
		(property "Footprint" ""
			(at 182.88 44.45 0)
			(effects
				(font
					(size 1.27 1.27)
				)
				(hide yes)
			)
		)
		(property "Datasheet" ""
			(at 182.88 44.45 0)
			(effects
				(font
					(size 1.27 1.27)
				)
				(hide yes)
			)
		)
		(property "Description" ""
			(at 182.88 44.45 0)
			(effects
				(font
					(size 1.27 1.27)
				)
				(hide yes)
			)
		)
		(pin "1"
		)
		(instances
			(project "thunderbolt-gpu-adapter"
				(path ""
					(reference "#FLG0107")
					(unit 1)
				)
			)
		)
	)
	(symbol
		(lib_id "antmicropower:GND")
		(at 223.52 326.39 0)
		(unit 1)
		(exclude_from_sim no)
		(in_bom yes)
		(on_board yes)
		(dnp no)
		(property "Reference" "#PWR075"
			(at 223.52 332.74 0)
			(effects
				(font
					(size 1.27 1.27)
				)
				(hide yes)
			)
		)
		(property "Value" "GND"
			(at 223.52 330.2 0)
			(effects
				(font
					(size 1.27 1.27)
				)
			)
		)
		(property "Footprint" ""
			(at 223.52 326.39 0)
			(effects
				(font
					(size 1.27 1.27)
				)
				(hide yes)
			)
		)
		(property "Datasheet" ""
			(at 223.52 326.39 0)
			(effects
				(font
					(size 1.27 1.27)
				)
				(hide yes)
			)
		)
		(property "Description" ""
			(at 223.52 326.39 0)
			(effects
				(font
					(size 1.27 1.27)
				)
				(hide yes)
			)
		)
		(property "Author" "Antmicro"
			(at 232.41 334.01 0)
			(effects
				(font
					(size 1.27 1.27)
					(thickness 0.15)
				)
				(justify left bottom)
				(hide yes)
			)
		)
		(property "License" "Apache-2.0"
			(at 232.41 336.55 0)
			(effects
				(font
					(size 1.27 1.27)
					(thickness 0.15)
				)
				(justify left bottom)
				(hide yes)
			)
		)
		(pin "1"
		)
		(instances
			(project "thunderbolt-gpu-adapter"
				(path ""
					(reference "#PWR075")
					(unit 1)
				)
			)
		)
	)
	(symbol
		(lib_id "antmicropower:GND")
		(at 190.5 364.49 0)
		(unit 1)
		(exclude_from_sim no)
		(in_bom yes)
		(on_board yes)
		(dnp no)
		(fields_autoplaced yes)
		(property "Reference" "#PWR068"
			(at 190.5 370.84 0)
			(effects
				(font
					(size 1.27 1.27)
				)
				(hide yes)
			)
		)
		(property "Value" "GND"
			(at 190.5 368.3 0)
			(effects
				(font
					(size 1.27 1.27)
				)
			)
		)
		(property "Footprint" ""
			(at 190.5 364.49 0)
			(effects
				(font
					(size 1.27 1.27)
				)
				(hide yes)
			)
		)
		(property "Datasheet" ""
			(at 190.5 364.49 0)
			(effects
				(font
					(size 1.27 1.27)
				)
				(hide yes)
			)
		)
		(property "Description" ""
			(at 190.5 364.49 0)
			(effects
				(font
					(size 1.27 1.27)
				)
				(hide yes)
			)
		)
		(property "Author" "Antmicro"
			(at 199.39 372.11 0)
			(effects
				(font
					(size 1.27 1.27)
					(thickness 0.15)
				)
				(justify left bottom)
				(hide yes)
			)
		)
		(property "License" "Apache-2.0"
			(at 199.39 374.65 0)
			(effects
				(font
					(size 1.27 1.27)
					(thickness 0.15)
				)
				(justify left bottom)
				(hide yes)
			)
		)
		(pin "1"
		)
		(instances
			(project "thunderbolt-gpu-adapter"
				(path ""
					(reference "#PWR068")
					(unit 1)
				)
			)
		)
	)
	(symbol
		(lib_id "antmicropower:GND")
		(at 99.06 363.22 0)
		(unit 1)
		(exclude_from_sim no)
		(in_bom yes)
		(on_board yes)
		(dnp no)
		(property "Reference" "#PWR0145"
			(at 99.06 369.57 0)
			(effects
				(font
					(size 1.27 1.27)
				)
				(hide yes)
			)
		)
		(property "Value" "GND"
			(at 99.06 367.03 0)
			(effects
				(font
					(size 1.27 1.27)
				)
			)
		)
		(property "Footprint" ""
			(at 99.06 363.22 0)
			(effects
				(font
					(size 1.27 1.27)
				)
				(hide yes)
			)
		)
		(property "Datasheet" ""
			(at 99.06 363.22 0)
			(effects
				(font
					(size 1.27 1.27)
				)
				(hide yes)
			)
		)
		(property "Description" ""
			(at 99.06 363.22 0)
			(effects
				(font
					(size 1.27 1.27)
				)
				(hide yes)
			)
		)
		(property "Author" "Antmicro"
			(at 107.95 370.84 0)
			(effects
				(font
					(size 1.27 1.27)
					(thickness 0.15)
				)
				(justify left bottom)
				(hide yes)
			)
		)
		(property "License" "Apache-2.0"
			(at 107.95 373.38 0)
			(effects
				(font
					(size 1.27 1.27)
					(thickness 0.15)
				)
				(justify left bottom)
				(hide yes)
			)
		)
		(pin "1"
		)
		(instances
			(project "thunderbolt-gpu-adapter"
				(path ""
					(reference "#PWR0145")
					(unit 1)
				)
			)
		)
	)
	(symbol
		(lib_id "antmicropower:GND")
		(at 66.04 207.01 0)
		(unit 1)
		(exclude_from_sim no)
		(in_bom yes)
		(on_board yes)
		(dnp no)
		(property "Reference" "#PWR0227"
			(at 66.04 213.36 0)
			(effects
				(font
					(size 1.27 1.27)
				)
				(hide yes)
			)
		)
		(property "Value" "GND"
			(at 64.135 211.455 0)
			(effects
				(font
					(size 1.27 1.27)
					(thickness 0.15)
				)
				(justify left bottom)
			)
		)
		(property "Footprint" ""
			(at 66.04 207.01 0)
			(effects
				(font
					(size 1.27 1.27)
					(thickness 0.15)
				)
				(justify left bottom)
				(hide yes)
			)
		)
		(property "Datasheet" ""
			(at 66.04 207.01 0)
			(effects
				(font
					(size 1.27 1.27)
					(thickness 0.15)
				)
				(justify left bottom)
				(hide yes)
			)
		)
		(property "Description" ""
			(at 66.04 207.01 0)
			(effects
				(font
					(size 1.27 1.27)
				)
				(hide yes)
			)
		)
		(property "Author" "Antmicro"
			(at 74.93 214.63 0)
			(effects
				(font
					(size 1.27 1.27)
					(thickness 0.15)
				)
				(justify left bottom)
				(hide yes)
			)
		)
		(property "License" "Apache-2.0"
			(at 74.93 217.17 0)
			(effects
				(font
					(size 1.27 1.27)
					(thickness 0.15)
				)
				(justify left bottom)
				(hide yes)
			)
		)
		(pin "1"
		)
		(instances
			(project "thunderbolt-gpu-adapter"
				(path ""
					(reference "#PWR0227")
					(unit 1)
				)
			)
		)
	)
	(symbol
		(lib_id "antmicroCapacitorspol:C_Pol_330u_6.3V_KEMET-T520-B")
		(at 27.94 334.01 270)
		(unit 1)
		(exclude_from_sim no)
		(in_bom yes)
		(on_board yes)
		(dnp no)
		(fields_autoplaced yes)
		(property "Reference" "C136"
			(at 25.4 334.7466 90)
			(effects
				(font
					(size 1.27 1.27)
					(thickness 0.15)
				)
				(justify right)
			)
		)
		(property "Value" "C_Pol_330u_6.3V_KEMET-T520-B"
			(at 25.4 347.98 0)
			(effects
				(font
					(size 1.27 1.27)
					(thickness 0.15)
				)
				(justify left bottom)
				(hide yes)
			)
		)
		(property "Footprint" "antmicro-footprints:C_Pol_EIA-B"
			(at 20.32 347.98 0)
			(effects
				(font
					(size 1.27 1.27)
					(thickness 0.15)
				)
				(justify left bottom)
				(hide yes)
			)
		)
		(property "Datasheet" "https://www.kemet.com/en/us/capacitors/product/T520B337M006ATE040.html"
			(at 17.78 347.98 0)
			(effects
				(font
					(size 1.27 1.27)
					(thickness 0.15)
				)
				(justify left bottom)
				(hide yes)
			)
		)
		(property "Description" ""
			(at 27.94 334.01 0)
			(effects
				(font
					(size 1.27 1.27)
				)
				(hide yes)
			)
		)
		(property "Val" "330u"
			(at 25.4 337.2866 90)
			(effects
				(font
					(size 1.27 1.27)
					(thickness 0.15)
				)
				(justify right)
			)
		)
		(property "MPN" "T520B337M006ATE040"
			(at 15.24 347.98 0)
			(effects
				(font
					(size 1.27 1.27)
					(thickness 0.15)
				)
				(justify left bottom)
				(hide yes)
			)
		)
		(property "Manufacturer" "KEMET"
			(at 12.7 347.98 0)
			(effects
				(font
					(size 1.27 1.27)
					(thickness 0.15)
				)
				(justify left bottom)
				(hide yes)
			)
		)
		(property "License" "Apache-2.0"
			(at 10.16 347.98 0)
			(effects
				(font
					(size 1.27 1.27)
					(thickness 0.15)
				)
				(justify left bottom)
				(hide yes)
			)
		)
		(property "Author" "Antmicro"
			(at 7.62 347.98 0)
			(effects
				(font
					(size 1.27 1.27)
					(thickness 0.15)
				)
				(justify left bottom)
				(hide yes)
			)
		)
		(property "Voltage" "6.3V"
			(at 5.08 347.98 0)
			(effects
				(font
					(size 1.27 1.27)
				)
				(justify left bottom)
				(hide yes)
			)
		)
		(property "Dielectric" "template_dielectric"
			(at 2.54 347.98 0)
			(effects
				(font
					(size 1.27 1.27)
				)
				(justify left bottom)
				(hide yes)
			)
		)
		(pin "1"
		)
		(pin "2"
		)
		(instances
			(project "thunderbolt-gpu-adapter"
				(path ""
					(reference "C136")
					(unit 1)
				)
			)
		)
	)
	(symbol
		(lib_id "antmicropower:GND")
		(at 46.99 394.97 0)
		(unit 1)
		(exclude_from_sim no)
		(in_bom yes)
		(on_board yes)
		(dnp no)
		(property "Reference" "#PWR0191"
			(at 46.99 401.32 0)
			(effects
				(font
					(size 1.27 1.27)
				)
				(hide yes)
			)
		)
		(property "Value" "GND"
			(at 46.99 398.78 0)
			(effects
				(font
					(size 1.27 1.27)
				)
			)
		)
		(property "Footprint" ""
			(at 46.99 394.97 0)
			(effects
				(font
					(size 1.27 1.27)
				)
				(hide yes)
			)
		)
		(property "Datasheet" ""
			(at 46.99 394.97 0)
			(effects
				(font
					(size 1.27 1.27)
				)
				(hide yes)
			)
		)
		(property "Description" ""
			(at 46.99 394.97 0)
			(effects
				(font
					(size 1.27 1.27)
				)
				(hide yes)
			)
		)
		(property "Author" "Antmicro"
			(at 55.88 402.59 0)
			(effects
				(font
					(size 1.27 1.27)
					(thickness 0.15)
				)
				(justify left bottom)
				(hide yes)
			)
		)
		(property "License" "Apache-2.0"
			(at 55.88 405.13 0)
			(effects
				(font
					(size 1.27 1.27)
					(thickness 0.15)
				)
				(justify left bottom)
				(hide yes)
			)
		)
		(pin "1"
		)
		(instances
			(project "thunderbolt-gpu-adapter"
				(path ""
					(reference "#PWR0191")
					(unit 1)
				)
			)
		)
	)
	(symbol
		(lib_id "antmicropower:PWR_FLAG")
		(at 60.96 43.18 0)
		(mirror y)
		(unit 1)
		(exclude_from_sim no)
		(in_bom yes)
		(on_board yes)
		(dnp no)
		(property "Reference" "#FLG0111"
			(at 60.96 41.275 0)
			(effects
				(font
					(size 1.27 1.27)
				)
				(hide yes)
			)
		)
		(property "Value" "PWR_FLAG"
			(at 53.34 42.545 0)
			(effects
				(font
					(size 1.27 1.27)
				)
			)
		)
		(property "Footprint" ""
			(at 60.96 43.18 0)
			(effects
				(font
					(size 1.27 1.27)
				)
				(hide yes)
			)
		)
		(property "Datasheet" ""
			(at 60.96 43.18 0)
			(effects
				(font
					(size 1.27 1.27)
				)
				(hide yes)
			)
		)
		(property "Description" ""
			(at 60.96 43.18 0)
			(effects
				(font
					(size 1.27 1.27)
				)
				(hide yes)
			)
		)
		(pin "1"
		)
		(instances
			(project "thunderbolt-gpu-adapter"
				(path ""
					(reference "#FLG0111")
					(unit 1)
				)
			)
		)
	)
	(symbol
		(lib_id "antmicroResistors0402:R_2k2_0402")
		(at 224.79 285.75 270)
		(mirror x)
		(unit 1)
		(exclude_from_sim no)
		(in_bom yes)
		(on_board yes)
		(dnp no)
		(property "Reference" "R97"
			(at 222.885 281.9399 90)
			(effects
				(font
					(size 1.27 1.27)
					(thickness 0.15)
				)
				(justify right)
			)
		)
		(property "Value" "R_2k2_0402"
			(at 212.09 265.43 0)
			(effects
				(font
					(size 1.27 1.27)
					(thickness 0.15)
				)
				(justify left bottom)
				(hide yes)
			)
		)
		(property "Footprint" "antmicro-footprints:R_0402_1005Metric"
			(at 209.55 265.43 0)
			(effects
				(font
					(size 1.27 1.27)
					(thickness 0.15)
				)
				(justify left bottom)
				(hide yes)
			)
		)
		(property "Datasheet" "https://www.bourns.com/docs/product-datasheets/cr.pdf"
			(at 207.01 265.43 0)
			(effects
				(font
					(size 1.27 1.27)
					(thickness 0.15)
				)
				(justify left bottom)
				(hide yes)
			)
		)
		(property "Description" ""
			(at 224.79 285.75 0)
			(effects
				(font
					(size 1.27 1.27)
				)
				(hide yes)
			)
		)
		(property "MPN" "CR0402-FX-2201GLF"
			(at 204.47 265.43 0)
			(effects
				(font
					(size 1.27 1.27)
					(thickness 0.15)
				)
				(justify left bottom)
				(hide yes)
			)
		)
		(property "Manufacturer" "Bourns"
			(at 201.93 265.43 0)
			(effects
				(font
					(size 1.27 1.27)
					(thickness 0.15)
				)
				(justify left bottom)
				(hide yes)
			)
		)
		(property "License" "Apache-2.0"
			(at 199.39 265.43 0)
			(effects
				(font
					(size 1.27 1.27)
					(thickness 0.15)
				)
				(justify left bottom)
				(hide yes)
			)
		)
		(property "Val" "2k2"
			(at 222.885 284.4799 90)
			(effects
				(font
					(size 1.27 1.27)
					(thickness 0.15)
				)
				(justify right)
			)
		)
		(property "Tolerance" "1%"
			(at 214.63 265.43 0)
			(effects
				(font
					(size 1.27 1.27)
				)
				(justify left bottom)
				(hide yes)
			)
		)
		(property "Author" "Antmicro"
			(at 196.85 265.43 0)
			(effects
				(font
					(size 1.27 1.27)
					(thickness 0.15)
				)
				(justify left bottom)
				(hide yes)
			)
		)
		(pin "1"
		)
		(pin "2"
		)
		(instances
			(project "thunderbolt-gpu-adapter"
				(path ""
					(reference "R97")
					(unit 1)
				)
			)
		)
	)
	(symbol
		(lib_id "antmicroPMICPowerDistributionSwitchesLoadDrivers:AP22615A_TSOT26")
		(at 224.79 118.11 0)
		(unit 1)
		(exclude_from_sim no)
		(in_bom yes)
		(on_board yes)
		(dnp no)
		(fields_autoplaced yes)
		(property "Reference" "U11"
			(at 232.41 110.49 0)
			(effects
				(font
					(size 1.27 1.27)
					(thickness 0.15)
				)
			)
		)
		(property "Value" "AP22615A_TSOT26"
			(at 255.27 123.19 0)
			(effects
				(font
					(size 1.27 1.27)
					(thickness 0.15)
				)
				(justify left bottom)
				(hide yes)
			)
		)
		(property "Footprint" "antmicro-footprints:TSOT23-6"
			(at 255.27 125.73 0)
			(effects
				(font
					(size 1.27 1.27)
					(thickness 0.15)
				)
				(justify left bottom)
				(hide yes)
			)
		)
		(property "Datasheet" "https://www.mouser.com/datasheet/2/115/DIOD_S_A0008958405_1-2543193.pdf"
			(at 255.27 128.27 0)
			(effects
				(font
					(size 1.27 1.27)
					(thickness 0.15)
				)
				(justify left bottom)
				(hide yes)
			)
		)
		(property "Description" ""
			(at 224.79 118.11 0)
			(effects
				(font
					(size 1.27 1.27)
				)
				(hide yes)
			)
		)
		(property "MPN" "AP22615AWU-7"
			(at 232.41 113.03 0)
			(effects
				(font
					(size 1.27 1.27)
					(thickness 0.15)
				)
			)
		)
		(property "Manufacturer" "Diodes Incorporated"
			(at 255.27 133.35 0)
			(effects
				(font
					(size 1.27 1.27)
					(thickness 0.15)
				)
				(justify left bottom)
				(hide yes)
			)
		)
		(property "Author" "Antmicro"
			(at 255.27 135.89 0)
			(effects
				(font
					(size 1.27 1.27)
					(thickness 0.15)
				)
				(justify left bottom)
				(hide yes)
			)
		)
		(property "License" "Apache-2.0"
			(at 255.27 138.43 0)
			(effects
				(font
					(size 1.27 1.27)
					(thickness 0.15)
				)
				(justify left bottom)
				(hide yes)
			)
		)
		(pin "1"
		)
		(pin "2"
		)
		(pin "3"
		)
		(pin "4"
		)
		(pin "5"
		)
		(pin "6"
		)
		(instances
			(project "thunderbolt-gpu-adapter"
				(path ""
					(reference "U11")
					(unit 1)
				)
			)
		)
	)
	(symbol
		(lib_id "antmicroCapacitors0603:C_22u_0603")
		(at 190.5 358.14 90)
		(unit 1)
		(exclude_from_sim no)
		(in_bom yes)
		(on_board yes)
		(dnp no)
		(fields_autoplaced yes)
		(property "Reference" "C47"
			(at 193.04 354.3236 90)
			(effects
				(font
					(size 1.27 1.27)
					(thickness 0.15)
				)
				(justify right)
			)
		)
		(property "Value" "C_22u_0603"
			(at 200.66 337.82 0)
			(effects
				(font
					(size 1.27 1.27)
					(thickness 0.15)
				)
				(justify left bottom)
				(hide yes)
			)
		)
		(property "Footprint" "antmicro-footprints:C_0603_1608Metric"
			(at 203.2 337.82 0)
			(effects
				(font
					(size 1.27 1.27)
					(thickness 0.15)
				)
				(justify left bottom)
				(hide yes)
			)
		)
		(property "Datasheet" "https://www.murata.com/products/productdetail?partno=GRM188R60J226MEA0%23"
			(at 205.74 337.82 0)
			(effects
				(font
					(size 1.27 1.27)
					(thickness 0.15)
				)
				(justify left bottom)
				(hide yes)
			)
		)
		(property "Description" ""
			(at 190.5 358.14 0)
			(effects
				(font
					(size 1.27 1.27)
				)
				(hide yes)
			)
		)
		(property "MPN" "GRM188R60J226MEA0D"
			(at 208.28 337.82 0)
			(effects
				(font
					(size 1.27 1.27)
					(thickness 0.15)
				)
				(justify left bottom)
				(hide yes)
			)
		)
		(property "Manufacturer" "Murata"
			(at 210.82 337.82 0)
			(effects
				(font
					(size 1.27 1.27)
					(thickness 0.15)
				)
				(justify left bottom)
				(hide yes)
			)
		)
		(property "License" "Apache-2.0"
			(at 213.36 337.82 0)
			(effects
				(font
					(size 1.27 1.27)
					(thickness 0.15)
				)
				(justify left bottom)
				(hide yes)
			)
		)
		(property "Val" "22u"
			(at 193.04 356.8636 90)
			(effects
				(font
					(size 1.27 1.27)
					(thickness 0.15)
				)
				(justify right)
			)
		)
		(property "Voltage" ""
			(at 218.44 337.82 0)
			(effects
				(font
					(size 1.27 1.27)
				)
				(justify left bottom)
				(hide yes)
			)
		)
		(property "Dielectric" ""
			(at 220.98 337.82 0)
			(effects
				(font
					(size 1.27 1.27)
				)
				(justify left bottom)
				(hide yes)
			)
		)
		(property "Author" "Antmicro"
			(at 215.9 337.82 0)
			(effects
				(font
					(size 1.27 1.27)
					(thickness 0.15)
				)
				(justify left bottom)
				(hide yes)
			)
		)
		(pin "1"
		)
		(pin "2"
		)
		(instances
			(project "thunderbolt-gpu-adapter"
				(path ""
					(reference "C47")
					(unit 1)
				)
			)
		)
	)
	(symbol
		(lib_id "antmicroCapacitors0402:C_4n7_0402")
		(at 172.72 256.54 90)
		(unit 1)
		(exclude_from_sim no)
		(in_bom yes)
		(on_board yes)
		(dnp no)
		(fields_autoplaced yes)
		(property "Reference" "C30"
			(at 175.26 252.7236 90)
			(effects
				(font
					(size 1.27 1.27)
					(thickness 0.15)
				)
				(justify right)
			)
		)
		(property "Value" "C_4n7_0402"
			(at 182.88 236.22 0)
			(effects
				(font
					(size 1.27 1.27)
					(thickness 0.15)
				)
				(justify left bottom)
				(hide yes)
			)
		)
		(property "Footprint" "antmicro-footprints:C_0402_1005Metric"
			(at 185.42 236.22 0)
			(effects
				(font
					(size 1.27 1.27)
					(thickness 0.15)
				)
				(justify left bottom)
				(hide yes)
			)
		)
		(property "Datasheet" "https://product.tdk.com/en/search/capacitor/ceramic/mlcc/info?part_no=CGA2B3X7S2A472K050BB"
			(at 187.96 236.22 0)
			(effects
				(font
					(size 1.27 1.27)
					(thickness 0.15)
				)
				(justify left bottom)
				(hide yes)
			)
		)
		(property "Description" ""
			(at 172.72 256.54 0)
			(effects
				(font
					(size 1.27 1.27)
				)
				(hide yes)
			)
		)
		(property "MPN" "CGA2B3X7S2A472K050BB"
			(at 190.5 236.22 0)
			(effects
				(font
					(size 1.27 1.27)
					(thickness 0.15)
				)
				(justify left bottom)
				(hide yes)
			)
		)
		(property "Manufacturer" "TDK"
			(at 193.04 236.22 0)
			(effects
				(font
					(size 1.27 1.27)
					(thickness 0.15)
				)
				(justify left bottom)
				(hide yes)
			)
		)
		(property "License" "Apache-2.0"
			(at 195.58 236.22 0)
			(effects
				(font
					(size 1.27 1.27)
					(thickness 0.15)
				)
				(justify left bottom)
				(hide yes)
			)
		)
		(property "Val" "4n7"
			(at 175.26 255.2636 90)
			(effects
				(font
					(size 1.27 1.27)
					(thickness 0.15)
				)
				(justify right)
			)
		)
		(property "Voltage" ""
			(at 200.66 236.22 0)
			(effects
				(font
					(size 1.27 1.27)
				)
				(justify left bottom)
				(hide yes)
			)
		)
		(property "Dielectric" ""
			(at 203.2 236.22 0)
			(effects
				(font
					(size 1.27 1.27)
				)
				(justify left bottom)
				(hide yes)
			)
		)
		(property "Author" "Antmicro"
			(at 198.12 236.22 0)
			(effects
				(font
					(size 1.27 1.27)
					(thickness 0.15)
				)
				(justify left bottom)
				(hide yes)
			)
		)
		(pin "1"
		)
		(pin "2"
		)
		(instances
			(project "thunderbolt-gpu-adapter"
				(path ""
					(reference "C30")
					(unit 1)
				)
			)
		)
	)
	(symbol
		(lib_id "antmicroResistors0402:R_10k_0402")
		(at 64.77 107.95 0)
		(unit 1)
		(exclude_from_sim no)
		(in_bom yes)
		(on_board yes)
		(dnp no)
		(property "Reference" "R19"
			(at 67.31 106.045 0)
			(effects
				(font
					(size 1.27 1.27)
					(thickness 0.15)
				)
			)
		)
		(property "Value" "R_10k_0402"
			(at 85.09 120.65 0)
			(effects
				(font
					(size 1.27 1.27)
					(thickness 0.15)
				)
				(justify left bottom)
				(hide yes)
			)
		)
		(property "Footprint" "antmicro-footprints:R_0402_1005Metric"
			(at 85.09 123.19 0)
			(effects
				(font
					(size 1.27 1.27)
					(thickness 0.15)
				)
				(justify left bottom)
				(hide yes)
			)
		)
		(property "Datasheet" "https://www.bourns.com/docs/product-datasheets/cr.pdf"
			(at 85.09 125.73 0)
			(effects
				(font
					(size 1.27 1.27)
					(thickness 0.15)
				)
				(justify left bottom)
				(hide yes)
			)
		)
		(property "Description" ""
			(at 64.77 107.95 0)
			(effects
				(font
					(size 1.27 1.27)
				)
				(hide yes)
			)
		)
		(property "MPN" "CR0402-FX-1002GLF"
			(at 85.09 128.27 0)
			(effects
				(font
					(size 1.27 1.27)
					(thickness 0.15)
				)
				(justify left bottom)
				(hide yes)
			)
		)
		(property "Manufacturer" "Bourns"
			(at 85.09 130.81 0)
			(effects
				(font
					(size 1.27 1.27)
					(thickness 0.15)
				)
				(justify left bottom)
				(hide yes)
			)
		)
		(property "License" "Apache-2.0"
			(at 85.09 133.35 0)
			(effects
				(font
					(size 1.27 1.27)
					(thickness 0.15)
				)
				(justify left bottom)
				(hide yes)
			)
		)
		(property "Val" "10k"
			(at 67.31 107.95 0)
			(effects
				(font
					(size 1.27 1.27)
					(thickness 0.15)
				)
			)
		)
		(property "Tolerance" "1%"
			(at 85.09 118.11 0)
			(effects
				(font
					(size 1.27 1.27)
				)
				(justify left bottom)
				(hide yes)
			)
		)
		(property "Author" "Antmicro"
			(at 85.09 135.89 0)
			(effects
				(font
					(size 1.27 1.27)
					(thickness 0.15)
				)
				(justify left bottom)
				(hide yes)
			)
		)
		(pin "1"
		)
		(pin "2"
		)
		(instances
			(project "thunderbolt-gpu-adapter"
				(path ""
					(reference "R19")
					(unit 1)
				)
			)
		)
	)
	(symbol
		(lib_id "antmicropower:GND")
		(at 57.15 252.73 0)
		(unit 1)
		(exclude_from_sim no)
		(in_bom yes)
		(on_board yes)
		(dnp no)
		(property "Reference" "#PWR0153"
			(at 57.15 259.08 0)
			(effects
				(font
					(size 1.27 1.27)
				)
				(hide yes)
			)
		)
		(property "Value" "GND"
			(at 57.15 256.54 0)
			(effects
				(font
					(size 1.27 1.27)
				)
			)
		)
		(property "Footprint" ""
			(at 57.15 252.73 0)
			(effects
				(font
					(size 1.27 1.27)
				)
				(hide yes)
			)
		)
		(property "Datasheet" ""
			(at 57.15 252.73 0)
			(effects
				(font
					(size 1.27 1.27)
				)
				(hide yes)
			)
		)
		(property "Description" ""
			(at 57.15 252.73 0)
			(effects
				(font
					(size 1.27 1.27)
				)
				(hide yes)
			)
		)
		(property "Author" "Antmicro"
			(at 66.04 260.35 0)
			(effects
				(font
					(size 1.27 1.27)
					(thickness 0.15)
				)
				(justify left bottom)
				(hide yes)
			)
		)
		(property "License" "Apache-2.0"
			(at 66.04 262.89 0)
			(effects
				(font
					(size 1.27 1.27)
					(thickness 0.15)
				)
				(justify left bottom)
				(hide yes)
			)
		)
		(pin "1"
		)
		(instances
			(project "thunderbolt-gpu-adapter"
				(path ""
					(reference "#PWR0153")
					(unit 1)
				)
			)
		)
	)
	(symbol
		(lib_id "antmicroTestPoints:TP_0.75mm_SMD")
		(at 127 228.6 0)
		(mirror y)
		(unit 1)
		(exclude_from_sim no)
		(in_bom no)
		(on_board yes)
		(dnp no)
		(property "Reference" "TP4"
			(at 123.19 228.6 0)
			(effects
				(font
					(size 1.27 1.27)
					(thickness 0.15)
				)
				(justify left)
			)
		)
		(property "Value" "TP_0.75mm_SMD"
			(at 121.92 228.5999 0)
			(effects
				(font
					(size 1.27 1.27)
					(thickness 0.15)
				)
				(justify left bottom)
				(hide yes)
			)
		)
		(property "Footprint" "antmicro-footprints:TP_SMD_0.75mm"
			(at 111.76 238.76 0)
			(effects
				(font
					(size 1.27 1.27)
					(thickness 0.15)
				)
				(justify left bottom)
				(hide yes)
			)
		)
		(property "Datasheet" ""
			(at 111.76 241.3 0)
			(effects
				(font
					(size 1.27 1.27)
					(thickness 0.15)
				)
				(justify left bottom)
				(hide yes)
			)
		)
		(property "Description" ""
			(at 127 228.6 0)
			(effects
				(font
					(size 1.27 1.27)
				)
				(hide yes)
			)
		)
		(property "License" "Apache-2.0"
			(at 111.76 246.38 0)
			(effects
				(font
					(size 1.27 1.27)
					(thickness 0.15)
				)
				(justify left bottom)
				(hide yes)
			)
		)
		(property "Manufacturer" ""
			(at 121.92 231.1399 0)
			(effects
				(font
					(size 1.27 1.27)
					(thickness 0.15)
				)
				(justify left bottom)
				(hide yes)
			)
		)
		(property "MPN" ""
			(at 127 228.6 0)
			(effects
				(font
					(size 1.27 1.27)
					(thickness 0.15)
				)
				(justify left bottom)
				(hide yes)
			)
		)
		(property "Author" "Antmicro"
			(at 111.76 243.84 0)
			(effects
				(font
					(size 1.27 1.27)
					(thickness 0.15)
				)
				(justify left bottom)
				(hide yes)
			)
		)
		(pin "1"
		)
		(instances
			(project "thunderbolt-gpu-adapter"
				(path ""
					(reference "TP4")
					(unit 1)
				)
			)
		)
	)
	(symbol
		(lib_id "antmicroCapacitors0402:C_100n_0402")
		(at 162.56 236.22 0)
		(mirror x)
		(unit 1)
		(exclude_from_sim no)
		(in_bom yes)
		(on_board yes)
		(dnp no)
		(property "Reference" "C28"
			(at 169.545 238.125 0)
			(effects
				(font
					(size 1.27 1.27)
					(thickness 0.15)
				)
				(justify right)
			)
		)
		(property "Value" "C_100n_0402"
			(at 182.88 226.06 0)
			(effects
				(font
					(size 1.27 1.27)
					(thickness 0.15)
				)
				(justify left bottom)
				(hide yes)
			)
		)
		(property "Footprint" "antmicro-footprints:C_0402_1005Metric"
			(at 182.88 223.52 0)
			(effects
				(font
					(size 1.27 1.27)
					(thickness 0.15)
				)
				(justify left bottom)
				(hide yes)
			)
		)
		(property "Datasheet" "https://www.murata.com/products/productdetail?partno=GRM155R61H104KE14%23"
			(at 182.88 220.98 0)
			(effects
				(font
					(size 1.27 1.27)
					(thickness 0.15)
				)
				(justify left bottom)
				(hide yes)
			)
		)
		(property "Description" ""
			(at 162.56 236.22 0)
			(effects
				(font
					(size 1.27 1.27)
				)
				(hide yes)
			)
		)
		(property "MPN" "GRM155R61H104KE14D"
			(at 182.88 218.44 0)
			(effects
				(font
					(size 1.27 1.27)
					(thickness 0.15)
				)
				(justify left bottom)
				(hide yes)
			)
		)
		(property "Manufacturer" "Murata"
			(at 182.88 215.9 0)
			(effects
				(font
					(size 1.27 1.27)
					(thickness 0.15)
				)
				(justify left bottom)
				(hide yes)
			)
		)
		(property "License" "Apache-2.0"
			(at 182.88 213.36 0)
			(effects
				(font
					(size 1.27 1.27)
					(thickness 0.15)
				)
				(justify left bottom)
				(hide yes)
			)
		)
		(property "Val" "100n"
			(at 159.385 237.49 0)
			(effects
				(font
					(size 1.27 1.27)
					(thickness 0.15)
				)
				(justify left bottom)
			)
		)
		(property "Voltage" "50V"
			(at 182.88 208.28 0)
			(effects
				(font
					(size 1.27 1.27)
				)
				(justify left bottom)
				(hide yes)
			)
		)
		(property "Dielectric" "X5R"
			(at 182.88 205.74 0)
			(effects
				(font
					(size 1.27 1.27)
				)
				(justify left bottom)
				(hide yes)
			)
		)
		(property "Author" "Antmicro"
			(at 182.88 210.82 0)
			(effects
				(font
					(size 1.27 1.27)
					(thickness 0.15)
				)
				(justify left bottom)
				(hide yes)
			)
		)
		(pin "1"
		)
		(pin "2"
		)
		(instances
			(project "thunderbolt-gpu-adapter"
				(path ""
					(reference "C28")
					(unit 1)
				)
			)
		)
	)
	(symbol
		(lib_id "antmicropower:GND")
		(at 162.56 88.9 0)
		(unit 1)
		(exclude_from_sim no)
		(in_bom yes)
		(on_board yes)
		(dnp no)
		(property "Reference" "#PWR066"
			(at 162.56 95.25 0)
			(effects
				(font
					(size 1.27 1.27)
				)
				(hide yes)
			)
		)
		(property "Value" "GND"
			(at 162.56 92.71 0)
			(effects
				(font
					(size 1.27 1.27)
				)
			)
		)
		(property "Footprint" ""
			(at 162.56 88.9 0)
			(effects
				(font
					(size 1.27 1.27)
				)
				(hide yes)
			)
		)
		(property "Datasheet" ""
			(at 162.56 88.9 0)
			(effects
				(font
					(size 1.27 1.27)
				)
				(hide yes)
			)
		)
		(property "Description" ""
			(at 162.56 88.9 0)
			(effects
				(font
					(size 1.27 1.27)
				)
				(hide yes)
			)
		)
		(property "Author" "Antmicro"
			(at 171.45 96.52 0)
			(effects
				(font
					(size 1.27 1.27)
					(thickness 0.15)
				)
				(justify left bottom)
				(hide yes)
			)
		)
		(property "License" "Apache-2.0"
			(at 171.45 99.06 0)
			(effects
				(font
					(size 1.27 1.27)
					(thickness 0.15)
				)
				(justify left bottom)
				(hide yes)
			)
		)
		(pin "1"
		)
		(instances
			(project "thunderbolt-gpu-adapter"
				(path ""
					(reference "#PWR066")
					(unit 1)
				)
			)
		)
	)
	(symbol
		(lib_id "antmicroCapacitorsmisc:C_22u_1206_35V")
		(at 55.88 204.47 90)
		(unit 1)
		(exclude_from_sim no)
		(in_bom yes)
		(on_board yes)
		(dnp yes)
		(fields_autoplaced yes)
		(property "Reference" "C10"
			(at 58.42 200.6536 90)
			(effects
				(font
					(size 1.27 1.27)
					(thickness 0.15)
				)
				(justify right)
			)
		)
		(property "Value" "C_22u_1206_35V"
			(at 66.04 184.15 0)
			(effects
				(font
					(size 1.27 1.27)
					(thickness 0.15)
				)
				(justify left bottom)
				(hide yes)
			)
		)
		(property "Footprint" "antmicro-footprints:C_1206_3216Metric"
			(at 68.58 184.15 0)
			(effects
				(font
					(size 1.27 1.27)
					(thickness 0.15)
				)
				(justify left bottom)
				(hide yes)
			)
		)
		(property "Datasheet" "https://product.tdk.com/en/search/capacitor/ceramic/mlcc/info?part_no=3216X5R1V226M160AC"
			(at 71.12 184.15 0)
			(effects
				(font
					(size 1.27 1.27)
					(thickness 0.15)
				)
				(justify left bottom)
				(hide yes)
			)
		)
		(property "Description" ""
			(at 55.88 204.47 0)
			(effects
				(font
					(size 1.27 1.27)
				)
				(hide yes)
			)
		)
		(property "MPN" "3216X5R1V226M160AC"
			(at 73.66 184.15 0)
			(effects
				(font
					(size 1.27 1.27)
					(thickness 0.15)
				)
				(justify left bottom)
				(hide yes)
			)
		)
		(property "Manufacturer" "TDK"
			(at 76.2 184.15 0)
			(effects
				(font
					(size 1.27 1.27)
					(thickness 0.15)
				)
				(justify left bottom)
				(hide yes)
			)
		)
		(property "License" "Apache-2.0"
			(at 78.74 184.15 0)
			(effects
				(font
					(size 1.27 1.27)
					(thickness 0.15)
				)
				(justify left bottom)
				(hide yes)
			)
		)
		(property "Val" "22u"
			(at 58.42 203.1936 90)
			(effects
				(font
					(size 1.27 1.27)
					(thickness 0.15)
				)
				(justify right)
			)
		)
		(property "Voltage" "35V"
			(at 83.82 184.15 0)
			(effects
				(font
					(size 1.27 1.27)
				)
				(justify left bottom)
				(hide yes)
			)
		)
		(property "Dielectric" ""
			(at 86.36 184.15 0)
			(effects
				(font
					(size 1.27 1.27)
				)
				(justify left bottom)
				(hide yes)
			)
		)
		(property "Author" "Antmicro"
			(at 81.28 184.15 0)
			(effects
				(font
					(size 1.27 1.27)
					(thickness 0.15)
				)
				(justify left bottom)
				(hide yes)
			)
		)
		(pin "1"
		)
		(pin "2"
		)
		(instances
			(project "thunderbolt-gpu-adapter"
				(path ""
					(reference "C10")
					(unit 1)
				)
			)
		)
	)
	(symbol
		(lib_id "antmicroResistors0402:R_10k_0402")
		(at 135.89 143.51 0)
		(unit 1)
		(exclude_from_sim no)
		(in_bom yes)
		(on_board yes)
		(dnp no)
		(property "Reference" "R32"
			(at 133.985 142.24 0)
			(effects
				(font
					(size 1.27 1.27)
					(thickness 0.15)
				)
			)
		)
		(property "Value" "R_10k_0402"
			(at 156.21 156.21 0)
			(effects
				(font
					(size 1.27 1.27)
					(thickness 0.15)
				)
				(justify left bottom)
				(hide yes)
			)
		)
		(property "Footprint" "antmicro-footprints:R_0402_1005Metric"
			(at 156.21 158.75 0)
			(effects
				(font
					(size 1.27 1.27)
					(thickness 0.15)
				)
				(justify left bottom)
				(hide yes)
			)
		)
		(property "Datasheet" "https://www.bourns.com/docs/product-datasheets/cr.pdf"
			(at 156.21 161.29 0)
			(effects
				(font
					(size 1.27 1.27)
					(thickness 0.15)
				)
				(justify left bottom)
				(hide yes)
			)
		)
		(property "Description" ""
			(at 135.89 143.51 0)
			(effects
				(font
					(size 1.27 1.27)
				)
				(hide yes)
			)
		)
		(property "MPN" "CR0402-FX-1002GLF"
			(at 156.21 163.83 0)
			(effects
				(font
					(size 1.27 1.27)
					(thickness 0.15)
				)
				(justify left bottom)
				(hide yes)
			)
		)
		(property "Manufacturer" "Bourns"
			(at 156.21 166.37 0)
			(effects
				(font
					(size 1.27 1.27)
					(thickness 0.15)
				)
				(justify left bottom)
				(hide yes)
			)
		)
		(property "License" "Apache-2.0"
			(at 156.21 168.91 0)
			(effects
				(font
					(size 1.27 1.27)
					(thickness 0.15)
				)
				(justify left bottom)
				(hide yes)
			)
		)
		(property "Val" "10k"
			(at 142.875 142.24 0)
			(effects
				(font
					(size 1.27 1.27)
					(thickness 0.15)
				)
			)
		)
		(property "Tolerance" "1%"
			(at 156.21 153.67 0)
			(effects
				(font
					(size 1.27 1.27)
				)
				(justify left bottom)
				(hide yes)
			)
		)
		(property "Author" "Antmicro"
			(at 156.21 171.45 0)
			(effects
				(font
					(size 1.27 1.27)
					(thickness 0.15)
				)
				(justify left bottom)
				(hide yes)
			)
		)
		(pin "1"
		)
		(pin "2"
		)
		(instances
			(project "thunderbolt-gpu-adapter"
				(path ""
					(reference "R32")
					(unit 1)
				)
			)
		)
	)
	(symbol
		(lib_id "antmicropower:GND")
		(at 232.41 287.02 0)
		(unit 1)
		(exclude_from_sim no)
		(in_bom yes)
		(on_board yes)
		(dnp no)
		(property "Reference" "#PWR0155"
			(at 232.41 293.37 0)
			(effects
				(font
					(size 1.27 1.27)
				)
				(hide yes)
			)
		)
		(property "Value" "GND"
			(at 232.41 290.83 0)
			(effects
				(font
					(size 1.27 1.27)
				)
			)
		)
		(property "Footprint" ""
			(at 232.41 287.02 0)
			(effects
				(font
					(size 1.27 1.27)
				)
				(hide yes)
			)
		)
		(property "Datasheet" ""
			(at 232.41 287.02 0)
			(effects
				(font
					(size 1.27 1.27)
				)
				(hide yes)
			)
		)
		(property "Description" ""
			(at 232.41 287.02 0)
			(effects
				(font
					(size 1.27 1.27)
				)
				(hide yes)
			)
		)
		(property "Author" "Antmicro"
			(at 241.3 294.64 0)
			(effects
				(font
					(size 1.27 1.27)
					(thickness 0.15)
				)
				(justify left bottom)
				(hide yes)
			)
		)
		(property "License" "Apache-2.0"
			(at 241.3 297.18 0)
			(effects
				(font
					(size 1.27 1.27)
					(thickness 0.15)
				)
				(justify left bottom)
				(hide yes)
			)
		)
		(pin "1"
		)
		(instances
			(project "thunderbolt-gpu-adapter"
				(path ""
					(reference "#PWR0155")
					(unit 1)
				)
			)
		)
	)
	(symbol
		(lib_id "antmicropower:GND")
		(at 148.59 59.69 0)
		(unit 1)
		(exclude_from_sim no)
		(in_bom yes)
		(on_board yes)
		(dnp no)
		(property "Reference" "#PWR051"
			(at 148.59 66.04 0)
			(effects
				(font
					(size 1.27 1.27)
				)
				(hide yes)
			)
		)
		(property "Value" "GND"
			(at 148.59 63.5 0)
			(effects
				(font
					(size 1.27 1.27)
				)
			)
		)
		(property "Footprint" ""
			(at 148.59 59.69 0)
			(effects
				(font
					(size 1.27 1.27)
				)
				(hide yes)
			)
		)
		(property "Datasheet" ""
			(at 148.59 59.69 0)
			(effects
				(font
					(size 1.27 1.27)
				)
				(hide yes)
			)
		)
		(property "Description" ""
			(at 148.59 59.69 0)
			(effects
				(font
					(size 1.27 1.27)
				)
				(hide yes)
			)
		)
		(property "Author" "Antmicro"
			(at 157.48 67.31 0)
			(effects
				(font
					(size 1.27 1.27)
					(thickness 0.15)
				)
				(justify left bottom)
				(hide yes)
			)
		)
		(property "License" "Apache-2.0"
			(at 157.48 69.85 0)
			(effects
				(font
					(size 1.27 1.27)
					(thickness 0.15)
				)
				(justify left bottom)
				(hide yes)
			)
		)
		(pin "1"
		)
		(instances
			(project "thunderbolt-gpu-adapter"
				(path ""
					(reference "#PWR051")
					(unit 1)
				)
			)
		)
	)
	(symbol
		(lib_id "antmicroFerriteBeadsandChips:FB_30Z_8.5A_Murata-BLM21SN_0805")
		(at 33.02 384.81 0)
		(mirror x)
		(unit 1)
		(exclude_from_sim no)
		(in_bom yes)
		(on_board yes)
		(dnp no)
		(property "Reference" "FB5"
			(at 35.56 379.73 0)
			(effects
				(font
					(size 1.27 1.27)
					(thickness 0.15)
				)
			)
		)
		(property "Value" "FB_30Z_8.5A_Murata-BLM21SN_0805"
			(at 35.56 378.46 0)
			(effects
				(font
					(size 1.27 1.27)
					(thickness 0.15)
				)
				(hide yes)
			)
		)
		(property "Footprint" "antmicro-footprints:FB_0805_2012Metric"
			(at 46.99 379.73 0)
			(effects
				(font
					(size 1.27 1.27)
					(thickness 0.15)
				)
				(justify left bottom)
				(hide yes)
			)
		)
		(property "Datasheet" "https://www.murata.com/en-sg/products/productdata/8796738977822/ENFA0005.pdf?1519270210000"
			(at 46.99 377.19 0)
			(effects
				(font
					(size 1.27 1.27)
					(thickness 0.15)
				)
				(justify left bottom)
				(hide yes)
			)
		)
		(property "Description" ""
			(at 33.02 384.81 0)
			(effects
				(font
					(size 1.27 1.27)
				)
				(hide yes)
			)
		)
		(property "MPN" "BLM21SN300SZ1D"
			(at 46.99 374.65 0)
			(effects
				(font
					(size 1.27 1.27)
					(thickness 0.15)
				)
				(justify left bottom)
				(hide yes)
			)
		)
		(property "Manufacturer" "Murata"
			(at 46.99 372.11 0)
			(effects
				(font
					(size 1.27 1.27)
					(thickness 0.15)
				)
				(justify left bottom)
				(hide yes)
			)
		)
		(property "License" "Apache-2.0"
			(at 46.99 367.03 0)
			(effects
				(font
					(size 1.27 1.27)
					(thickness 0.15)
				)
				(justify left bottom)
				(hide yes)
			)
		)
		(property "Author" "Antmicro"
			(at 46.99 369.57 0)
			(effects
				(font
					(size 1.27 1.27)
					(thickness 0.15)
				)
				(justify left bottom)
				(hide yes)
			)
		)
		(property "Val" "30Z/8.5A"
			(at 30.48 381 0)
			(effects
				(font
					(size 1.27 1.27)
				)
				(justify left bottom)
			)
		)
		(property "Current" ""
			(at 53.34 361.95 0)
			(effects
				(font
					(size 1.27 1.27)
					(thickness 0.15)
				)
				(justify left bottom)
				(hide yes)
			)
		)
		(pin "1"
		)
		(pin "2"
		)
		(instances
			(project "thunderbolt-gpu-adapter"
				(path ""
					(reference "FB5")
					(unit 1)
				)
			)
		)
	)
	(symbol
		(lib_id "antmicroResistors0402:R_100k_0402")
		(at 57.15 251.46 90)
		(unit 1)
		(exclude_from_sim no)
		(in_bom yes)
		(on_board yes)
		(dnp no)
		(fields_autoplaced yes)
		(property "Reference" "R92"
			(at 54.61 247.65 90)
			(effects
				(font
					(size 1.27 1.27)
					(thickness 0.15)
				)
				(justify left)
			)
		)
		(property "Value" "R_100k_0402"
			(at 69.85 231.14 0)
			(effects
				(font
					(size 1.27 1.27)
					(thickness 0.15)
				)
				(justify left bottom)
				(hide yes)
			)
		)
		(property "Footprint" "antmicro-footprints:R_0402_1005Metric"
			(at 72.39 231.14 0)
			(effects
				(font
					(size 1.27 1.27)
					(thickness 0.15)
				)
				(justify left bottom)
				(hide yes)
			)
		)
		(property "Datasheet" "https://www.bourns.com/docs/product-datasheets/cr.pdf"
			(at 74.93 231.14 0)
			(effects
				(font
					(size 1.27 1.27)
					(thickness 0.15)
				)
				(justify left bottom)
				(hide yes)
			)
		)
		(property "Description" ""
			(at 57.15 251.46 0)
			(effects
				(font
					(size 1.27 1.27)
				)
				(hide yes)
			)
		)
		(property "MPN" "CR0402-FX-1003GLF"
			(at 77.47 231.14 0)
			(effects
				(font
					(size 1.27 1.27)
					(thickness 0.15)
				)
				(justify left bottom)
				(hide yes)
			)
		)
		(property "Manufacturer" "Bourns"
			(at 80.01 231.14 0)
			(effects
				(font
					(size 1.27 1.27)
					(thickness 0.15)
				)
				(justify left bottom)
				(hide yes)
			)
		)
		(property "License" "Apache-2.0"
			(at 82.55 231.14 0)
			(effects
				(font
					(size 1.27 1.27)
					(thickness 0.15)
				)
				(justify left bottom)
				(hide yes)
			)
		)
		(property "Val" "100k"
			(at 54.61 250.19 90)
			(effects
				(font
					(size 1.27 1.27)
					(thickness 0.15)
				)
				(justify left)
			)
		)
		(property "Tolerance" "1%"
			(at 67.31 231.14 0)
			(effects
				(font
					(size 1.27 1.27)
				)
				(justify left bottom)
				(hide yes)
			)
		)
		(property "Author" "Antmicro"
			(at 85.09 231.14 0)
			(effects
				(font
					(size 1.27 1.27)
					(thickness 0.15)
				)
				(justify left bottom)
				(hide yes)
			)
		)
		(pin "1"
		)
		(pin "2"
		)
		(instances
			(project "thunderbolt-gpu-adapter"
				(path ""
					(reference "R92")
					(unit 1)
				)
			)
		)
	)
	(symbol
		(lib_id "antmicropower:GND")
		(at 196.85 120.65 0)
		(unit 1)
		(exclude_from_sim no)
		(in_bom yes)
		(on_board yes)
		(dnp no)
		(property "Reference" "#PWR0166"
			(at 196.85 127 0)
			(effects
				(font
					(size 1.27 1.27)
				)
				(hide yes)
			)
		)
		(property "Value" "GND"
			(at 196.85 124.46 0)
			(effects
				(font
					(size 1.27 1.27)
				)
			)
		)
		(property "Footprint" ""
			(at 196.85 120.65 0)
			(effects
				(font
					(size 1.27 1.27)
				)
				(hide yes)
			)
		)
		(property "Datasheet" ""
			(at 196.85 120.65 0)
			(effects
				(font
					(size 1.27 1.27)
				)
				(hide yes)
			)
		)
		(property "Description" ""
			(at 196.85 120.65 0)
			(effects
				(font
					(size 1.27 1.27)
				)
				(hide yes)
			)
		)
		(property "Author" "Antmicro"
			(at 205.74 128.27 0)
			(effects
				(font
					(size 1.27 1.27)
					(thickness 0.15)
				)
				(justify left bottom)
				(hide yes)
			)
		)
		(property "License" "Apache-2.0"
			(at 205.74 130.81 0)
			(effects
				(font
					(size 1.27 1.27)
					(thickness 0.15)
				)
				(justify left bottom)
				(hide yes)
			)
		)
		(pin "1"
		)
		(instances
			(project "thunderbolt-gpu-adapter"
				(path ""
					(reference "#PWR0166")
					(unit 1)
				)
			)
		)
	)
	(symbol
		(lib_id "antmicroInterfaceControllers:TPS65983BAZBHR")
		(at 73.66 41.91 0)
		(unit 1)
		(exclude_from_sim no)
		(in_bom yes)
		(on_board yes)
		(dnp no)
		(fields_autoplaced yes)
		(property "Reference" "U3"
			(at 102.87 31.75 0)
			(effects
				(font
					(size 1.27 1.27)
					(thickness 0.15)
				)
			)
		)
		(property "Value" "TPS65983BAZBHR"
			(at 147.32 41.91 0)
			(effects
				(font
					(size 1.27 1.27)
					(thickness 0.15)
				)
				(justify left bottom)
				(hide yes)
			)
		)
		(property "Footprint" "antmicro-footprints:IC_TPS65983BAZBHR"
			(at 147.32 44.45 0)
			(effects
				(font
					(size 1.27 1.27)
					(thickness 0.15)
				)
				(justify left bottom)
				(hide yes)
			)
		)
		(property "Datasheet" "https://www.ti.com/lit/ds/symlink/tps65983b.pdf?ts=1678712702533&ref_url=https%253A%252F%252Fwww.ti.com%252Fproduct%252FTPS65983B"
			(at 147.32 46.99 0)
			(effects
				(font
					(size 1.27 1.27)
					(thickness 0.15)
				)
				(justify left bottom)
				(hide yes)
			)
		)
		(property "Description" ""
			(at 73.66 41.91 0)
			(effects
				(font
					(size 1.27 1.27)
				)
				(hide yes)
			)
		)
		(property "MPN" "TPS65983BAZBHR"
			(at 102.87 34.29 0)
			(effects
				(font
					(size 1.27 1.27)
					(thickness 0.15)
				)
			)
		)
		(property "Manufacturer" "Texas Instruments"
			(at 147.32 52.07 0)
			(effects
				(font
					(size 1.27 1.27)
					(thickness 0.15)
				)
				(justify left bottom)
				(hide yes)
			)
		)
		(property "License" "Apache-2.0"
			(at 147.32 57.15 0)
			(effects
				(font
					(size 1.27 1.27)
					(thickness 0.15)
				)
				(justify left bottom)
				(hide yes)
			)
		)
		(property "Author" "Antmicro"
			(at 147.32 54.61 0)
			(effects
				(font
					(size 1.27 1.27)
					(thickness 0.15)
				)
				(justify left bottom)
				(hide yes)
			)
		)
		(pin "A1"
		)
		(pin "A10"
		)
		(pin "A11"
		)
		(pin "A2"
		)
		(pin "A3"
		)
		(pin "A4"
		)
		(pin "A5"
		)
		(pin "A6"
		)
		(pin "A7"
		)
		(pin "A8"
		)
		(pin "A9"
		)
		(pin "B1"
		)
		(pin "B10"
		)
		(pin "B11"
		)
		(pin "B2"
		)
		(pin "B3"
		)
		(pin "B4"
		)
		(pin "B5"
		)
		(pin "B6"
		)
		(pin "B7"
		)
		(pin "B8"
		)
		(pin "B9"
		)
		(pin "C1"
		)
		(pin "C10"
		)
		(pin "C11"
		)
		(pin "C2"
		)
		(pin "D1"
		)
		(pin "D10"
		)
		(pin "D11"
		)
		(pin "D2"
		)
		(pin "D5"
		)
		(pin "D6"
		)
		(pin "D7"
		)
		(pin "D8"
		)
		(pin "E1"
		)
		(pin "E10"
		)
		(pin "E11"
		)
		(pin "E2"
		)
		(pin "E4"
		)
		(pin "E5"
		)
		(pin "E6"
		)
		(pin "E7"
		)
		(pin "E8"
		)
		(pin "F1"
		)
		(pin "F10"
		)
		(pin "F11"
		)
		(pin "F2"
		)
		(pin "F4"
		)
		(pin "F5"
		)
		(pin "F6"
		)
		(pin "F7"
		)
		(pin "F8"
		)
		(pin "G1"
		)
		(pin "G10"
		)
		(pin "G11"
		)
		(pin "G2"
		)
		(pin "G4"
		)
		(pin "G5"
		)
		(pin "G6"
		)
		(pin "G7"
		)
		(pin "G8"
		)
		(pin "H1"
		)
		(pin "H10"
		)
		(pin "H11"
		)
		(pin "H2"
		)
		(pin "H4"
		)
		(pin "H5"
		)
		(pin "H6"
		)
		(pin "H7"
		)
		(pin "H8"
		)
		(pin "J1"
		)
		(pin "J10"
		)
		(pin "J11"
		)
		(pin "J2"
		)
		(pin "K1"
		)
		(pin "K10"
		)
		(pin "K11"
		)
		(pin "K2"
		)
		(pin "K3"
		)
		(pin "K4"
		)
		(pin "K5"
		)
		(pin "K6"
		)
		(pin "K7"
		)
		(pin "K8"
		)
		(pin "K9"
		)
		(pin "L1"
		)
		(pin "L10"
		)
		(pin "L11"
		)
		(pin "L2"
		)
		(pin "L3"
		)
		(pin "L4"
		)
		(pin "L5"
		)
		(pin "L6"
		)
		(pin "L7"
		)
		(pin "L8"
		)
		(pin "L9"
		)
		(instances
			(project "thunderbolt-gpu-adapter"
				(path ""
					(reference "U3")
					(unit 1)
				)
			)
		)
	)
	(symbol
		(lib_id "antmicroTransistorsFETsMOSFETsSingle:SI7613DN-T1-GE3")
		(at 250.19 308.61 90)
		(unit 1)
		(exclude_from_sim no)
		(in_bom yes)
		(on_board yes)
		(dnp no)
		(fields_autoplaced yes)
		(property "Reference" "Q6"
			(at 247.65 294.64 90)
			(effects
				(font
					(size 1.524 1.524)
				)
			)
		)
		(property "Value" "SI7613DN-T1-GE3"
			(at 247.65 293.37 0)
			(effects
				(font
					(size 1.27 1.27)
					(thickness 0.15)
				)
				(justify left bottom)
				(hide yes)
			)
		)
		(property "Footprint" "antmicro-footprints:Vishay_PowerPAK_1212-8_Single"
			(at 248.92 293.37 0)
			(effects
				(font
					(size 1.27 1.27)
					(thickness 0.15)
				)
				(justify left bottom)
				(hide yes)
			)
		)
		(property "Datasheet" "https://www.vishay.com/docs/64809/si7613dn.pdf"
			(at 251.46 293.37 0)
			(effects
				(font
					(size 1.27 1.27)
					(thickness 0.15)
				)
				(justify left bottom)
				(hide yes)
			)
		)
		(property "Description" ""
			(at 250.19 308.61 0)
			(effects
				(font
					(size 1.27 1.27)
				)
				(hide yes)
			)
		)
		(property "MPN" "SI7613DN-T1-GE3"
			(at 247.65 297.18 90)
			(effects
				(font
					(size 1.27 1.27)
					(thickness 0.15)
				)
			)
		)
		(property "Manufacturer" "Vishay"
			(at 257.81 293.37 0)
			(effects
				(font
					(size 1.27 1.27)
					(thickness 0.15)
				)
				(justify left bottom)
				(hide yes)
			)
		)
		(property "Author" "Antmicro"
			(at 260.35 293.37 0)
			(effects
				(font
					(size 1.27 1.27)
					(thickness 0.15)
				)
				(justify left bottom)
				(hide yes)
			)
		)
		(property "License" "Apache-2.0"
			(at 262.89 293.37 0)
			(effects
				(font
					(size 1.27 1.27)
					(thickness 0.15)
				)
				(justify left bottom)
				(hide yes)
			)
		)
		(pin "1"
		)
		(pin "2"
		)
		(pin "3"
		)
		(pin "4"
		)
		(pin "5"
		)
		(instances
			(project "thunderbolt-gpu-adapter"
				(path ""
					(reference "Q6")
					(unit 1)
				)
			)
		)
	)
	(symbol
		(lib_id "antmicropower:GND")
		(at 172.72 257.81 0)
		(unit 1)
		(exclude_from_sim no)
		(in_bom yes)
		(on_board yes)
		(dnp no)
		(property "Reference" "#PWR0238"
			(at 172.72 264.16 0)
			(effects
				(font
					(size 1.27 1.27)
				)
				(hide yes)
			)
		)
		(property "Value" "GND"
			(at 170.815 262.255 0)
			(effects
				(font
					(size 1.27 1.27)
					(thickness 0.15)
				)
				(justify left bottom)
			)
		)
		(property "Footprint" ""
			(at 172.72 257.81 0)
			(effects
				(font
					(size 1.27 1.27)
					(thickness 0.15)
				)
				(justify left bottom)
				(hide yes)
			)
		)
		(property "Datasheet" ""
			(at 172.72 257.81 0)
			(effects
				(font
					(size 1.27 1.27)
					(thickness 0.15)
				)
				(justify left bottom)
				(hide yes)
			)
		)
		(property "Description" ""
			(at 172.72 257.81 0)
			(effects
				(font
					(size 1.27 1.27)
				)
				(hide yes)
			)
		)
		(property "Author" "Antmicro"
			(at 181.61 265.43 0)
			(effects
				(font
					(size 1.27 1.27)
					(thickness 0.15)
				)
				(justify left bottom)
				(hide yes)
			)
		)
		(property "License" "Apache-2.0"
			(at 181.61 267.97 0)
			(effects
				(font
					(size 1.27 1.27)
					(thickness 0.15)
				)
				(justify left bottom)
				(hide yes)
			)
		)
		(pin "1"
		)
		(instances
			(project "thunderbolt-gpu-adapter"
				(path ""
					(reference "#PWR0238")
					(unit 1)
				)
			)
		)
	)
	(symbol
		(lib_id "antmicropower:GND")
		(at 91.44 394.97 0)
		(unit 1)
		(exclude_from_sim no)
		(in_bom yes)
		(on_board yes)
		(dnp no)
		(property "Reference" "#PWR0190"
			(at 91.44 401.32 0)
			(effects
				(font
					(size 1.27 1.27)
				)
				(hide yes)
			)
		)
		(property "Value" "GND"
			(at 91.44 398.78 0)
			(effects
				(font
					(size 1.27 1.27)
				)
			)
		)
		(property "Footprint" ""
			(at 91.44 394.97 0)
			(effects
				(font
					(size 1.27 1.27)
				)
				(hide yes)
			)
		)
		(property "Datasheet" ""
			(at 91.44 394.97 0)
			(effects
				(font
					(size 1.27 1.27)
				)
				(hide yes)
			)
		)
		(property "Description" ""
			(at 91.44 394.97 0)
			(effects
				(font
					(size 1.27 1.27)
				)
				(hide yes)
			)
		)
		(property "Author" "Antmicro"
			(at 100.33 402.59 0)
			(effects
				(font
					(size 1.27 1.27)
					(thickness 0.15)
				)
				(justify left bottom)
				(hide yes)
			)
		)
		(property "License" "Apache-2.0"
			(at 100.33 405.13 0)
			(effects
				(font
					(size 1.27 1.27)
					(thickness 0.15)
				)
				(justify left bottom)
				(hide yes)
			)
		)
		(pin "1"
		)
		(instances
			(project "thunderbolt-gpu-adapter"
				(path ""
					(reference "#PWR0190")
					(unit 1)
				)
			)
		)
	)
	(symbol
		(lib_id "antmicropower:GND")
		(at 154.94 88.9 0)
		(unit 1)
		(exclude_from_sim no)
		(in_bom yes)
		(on_board yes)
		(dnp no)
		(property "Reference" "#PWR062"
			(at 154.94 95.25 0)
			(effects
				(font
					(size 1.27 1.27)
				)
				(hide yes)
			)
		)
		(property "Value" "GND"
			(at 154.94 92.71 0)
			(effects
				(font
					(size 1.27 1.27)
				)
			)
		)
		(property "Footprint" ""
			(at 154.94 88.9 0)
			(effects
				(font
					(size 1.27 1.27)
				)
				(hide yes)
			)
		)
		(property "Datasheet" ""
			(at 154.94 88.9 0)
			(effects
				(font
					(size 1.27 1.27)
				)
				(hide yes)
			)
		)
		(property "Description" ""
			(at 154.94 88.9 0)
			(effects
				(font
					(size 1.27 1.27)
				)
				(hide yes)
			)
		)
		(property "Author" "Antmicro"
			(at 163.83 96.52 0)
			(effects
				(font
					(size 1.27 1.27)
					(thickness 0.15)
				)
				(justify left bottom)
				(hide yes)
			)
		)
		(property "License" "Apache-2.0"
			(at 163.83 99.06 0)
			(effects
				(font
					(size 1.27 1.27)
					(thickness 0.15)
				)
				(justify left bottom)
				(hide yes)
			)
		)
		(pin "1"
		)
		(instances
			(project "thunderbolt-gpu-adapter"
				(path ""
					(reference "#PWR062")
					(unit 1)
				)
			)
		)
	)
	(symbol
		(lib_id "antmicroResistors0402:R_10k_0402")
		(at 64.77 87.63 0)
		(unit 1)
		(exclude_from_sim no)
		(in_bom yes)
		(on_board yes)
		(dnp no)
		(property "Reference" "R16"
			(at 63.5 86.36 0)
			(effects
				(font
					(size 1.27 1.27)
					(thickness 0.15)
				)
			)
		)
		(property "Value" "R_10k_0402"
			(at 85.09 100.33 0)
			(effects
				(font
					(size 1.27 1.27)
					(thickness 0.15)
				)
				(justify left bottom)
				(hide yes)
			)
		)
		(property "Footprint" "antmicro-footprints:R_0402_1005Metric"
			(at 85.09 102.87 0)
			(effects
				(font
					(size 1.27 1.27)
					(thickness 0.15)
				)
				(justify left bottom)
				(hide yes)
			)
		)
		(property "Datasheet" "https://www.bourns.com/docs/product-datasheets/cr.pdf"
			(at 85.09 105.41 0)
			(effects
				(font
					(size 1.27 1.27)
					(thickness 0.15)
				)
				(justify left bottom)
				(hide yes)
			)
		)
		(property "Description" ""
			(at 64.77 87.63 0)
			(effects
				(font
					(size 1.27 1.27)
				)
				(hide yes)
			)
		)
		(property "MPN" "CR0402-FX-1002GLF"
			(at 85.09 107.95 0)
			(effects
				(font
					(size 1.27 1.27)
					(thickness 0.15)
				)
				(justify left bottom)
				(hide yes)
			)
		)
		(property "Manufacturer" "Bourns"
			(at 85.09 110.49 0)
			(effects
				(font
					(size 1.27 1.27)
					(thickness 0.15)
				)
				(justify left bottom)
				(hide yes)
			)
		)
		(property "License" "Apache-2.0"
			(at 85.09 113.03 0)
			(effects
				(font
					(size 1.27 1.27)
					(thickness 0.15)
				)
				(justify left bottom)
				(hide yes)
			)
		)
		(property "Val" "10k"
			(at 71.12 86.36 0)
			(effects
				(font
					(size 1.27 1.27)
					(thickness 0.15)
				)
			)
		)
		(property "Tolerance" "1%"
			(at 85.09 97.79 0)
			(effects
				(font
					(size 1.27 1.27)
				)
				(justify left bottom)
				(hide yes)
			)
		)
		(property "Author" "Antmicro"
			(at 85.09 115.57 0)
			(effects
				(font
					(size 1.27 1.27)
					(thickness 0.15)
				)
				(justify left bottom)
				(hide yes)
			)
		)
		(pin "1"
		)
		(pin "2"
		)
		(instances
			(project "thunderbolt-gpu-adapter"
				(path ""
					(reference "R16")
					(unit 1)
				)
			)
		)
	)
	(symbol
		(lib_id "antmicroCapacitors0402:C_220p_0402")
		(at 181.61 87.63 90)
		(unit 1)
		(exclude_from_sim no)
		(in_bom yes)
		(on_board yes)
		(dnp no)
		(fields_autoplaced yes)
		(property "Reference" "C49"
			(at 184.15 83.8136 90)
			(effects
				(font
					(size 1.27 1.27)
					(thickness 0.15)
				)
				(justify right)
			)
		)
		(property "Value" "C_220p_0402"
			(at 191.77 67.31 0)
			(effects
				(font
					(size 1.27 1.27)
					(thickness 0.15)
				)
				(justify left bottom)
				(hide yes)
			)
		)
		(property "Footprint" "antmicro-footprints:C_0402_1005Metric"
			(at 194.31 67.31 0)
			(effects
				(font
					(size 1.27 1.27)
					(thickness 0.15)
				)
				(justify left bottom)
				(hide yes)
			)
		)
		(property "Datasheet" "https://spicat.kyocera-avx.com/product/mlcc/chartview/04025C221JAT2A/"
			(at 196.85 67.31 0)
			(effects
				(font
					(size 1.27 1.27)
					(thickness 0.15)
				)
				(justify left bottom)
				(hide yes)
			)
		)
		(property "Description" ""
			(at 181.61 87.63 0)
			(effects
				(font
					(size 1.27 1.27)
				)
				(hide yes)
			)
		)
		(property "MPN" "04025C221JAT2A"
			(at 199.39 67.31 0)
			(effects
				(font
					(size 1.27 1.27)
					(thickness 0.15)
				)
				(justify left bottom)
				(hide yes)
			)
		)
		(property "Manufacturer" "KYOCERA AVX"
			(at 201.93 67.31 0)
			(effects
				(font
					(size 1.27 1.27)
					(thickness 0.15)
				)
				(justify left bottom)
				(hide yes)
			)
		)
		(property "License" "Apache-2.0"
			(at 204.47 67.31 0)
			(effects
				(font
					(size 1.27 1.27)
					(thickness 0.15)
				)
				(justify left bottom)
				(hide yes)
			)
		)
		(property "Val" "220p"
			(at 184.15 86.3536 90)
			(effects
				(font
					(size 1.27 1.27)
					(thickness 0.15)
				)
				(justify right)
			)
		)
		(property "Voltage" ""
			(at 209.55 67.31 0)
			(effects
				(font
					(size 1.27 1.27)
				)
				(justify left bottom)
				(hide yes)
			)
		)
		(property "Dielectric" ""
			(at 212.09 67.31 0)
			(effects
				(font
					(size 1.27 1.27)
				)
				(justify left bottom)
				(hide yes)
			)
		)
		(property "Author" "Antmicro"
			(at 207.01 67.31 0)
			(effects
				(font
					(size 1.27 1.27)
					(thickness 0.15)
				)
				(justify left bottom)
				(hide yes)
			)
		)
		(pin "1"
		)
		(pin "2"
		)
		(instances
			(project "thunderbolt-gpu-adapter"
				(path ""
					(reference "C49")
					(unit 1)
				)
			)
		)
	)
	(symbol
		(lib_id "antmicroCapacitors0402:C_100n_0402")
		(at 46.99 66.04 90)
		(unit 1)
		(exclude_from_sim no)
		(in_bom yes)
		(on_board yes)
		(dnp no)
		(property "Reference" "C147"
			(at 46.99 61.595 90)
			(effects
				(font
					(size 1.27 1.27)
					(thickness 0.15)
				)
				(justify right)
			)
		)
		(property "Value" "C_100n_0402"
			(at 57.15 45.72 0)
			(effects
				(font
					(size 1.27 1.27)
					(thickness 0.15)
				)
				(justify left bottom)
				(hide yes)
			)
		)
		(property "Footprint" "antmicro-footprints:C_0402_1005Metric"
			(at 59.69 45.72 0)
			(effects
				(font
					(size 1.27 1.27)
					(thickness 0.15)
				)
				(justify left bottom)
				(hide yes)
			)
		)
		(property "Datasheet" "https://www.murata.com/products/productdetail?partno=GRM155R61H104KE14%23"
			(at 62.23 45.72 0)
			(effects
				(font
					(size 1.27 1.27)
					(thickness 0.15)
				)
				(justify left bottom)
				(hide yes)
			)
		)
		(property "Description" ""
			(at 46.99 66.04 0)
			(effects
				(font
					(size 1.27 1.27)
				)
				(hide yes)
			)
		)
		(property "MPN" "GRM155R61H104KE14D"
			(at 64.77 45.72 0)
			(effects
				(font
					(size 1.27 1.27)
					(thickness 0.15)
				)
				(justify left bottom)
				(hide yes)
			)
		)
		(property "Manufacturer" "Murata"
			(at 67.31 45.72 0)
			(effects
				(font
					(size 1.27 1.27)
					(thickness 0.15)
				)
				(justify left bottom)
				(hide yes)
			)
		)
		(property "License" "Apache-2.0"
			(at 69.85 45.72 0)
			(effects
				(font
					(size 1.27 1.27)
					(thickness 0.15)
				)
				(justify left bottom)
				(hide yes)
			)
		)
		(property "Author" "Antmicro"
			(at 72.39 45.72 0)
			(effects
				(font
					(size 1.27 1.27)
					(thickness 0.15)
				)
				(justify left bottom)
				(hide yes)
			)
		)
		(property "Val" "100n"
			(at 46.99 65.405 90)
			(effects
				(font
					(size 1.27 1.27)
					(thickness 0.15)
				)
				(justify right)
			)
		)
		(property "Voltage" "50V"
			(at 74.93 45.72 0)
			(effects
				(font
					(size 1.27 1.27)
				)
				(justify left bottom)
				(hide yes)
			)
		)
		(property "Dielectric" "X5R"
			(at 77.47 45.72 0)
			(effects
				(font
					(size 1.27 1.27)
				)
				(justify left bottom)
				(hide yes)
			)
		)
		(pin "1"
		)
		(pin "2"
		)
		(instances
			(project "thunderbolt-gpu-adapter"
				(path ""
					(reference "C147")
					(unit 1)
				)
			)
		)
	)
	(symbol
		(lib_id "antmicropower:GND")
		(at 153.67 58.42 0)
		(unit 1)
		(exclude_from_sim no)
		(in_bom yes)
		(on_board yes)
		(dnp no)
		(property "Reference" "#PWR0218"
			(at 153.67 64.77 0)
			(effects
				(font
					(size 1.27 1.27)
				)
				(hide yes)
			)
		)
		(property "Value" "GND"
			(at 153.67 62.23 0)
			(effects
				(font
					(size 1.27 1.27)
				)
			)
		)
		(property "Footprint" ""
			(at 153.67 58.42 0)
			(effects
				(font
					(size 1.27 1.27)
				)
				(hide yes)
			)
		)
		(property "Datasheet" ""
			(at 153.67 58.42 0)
			(effects
				(font
					(size 1.27 1.27)
				)
				(hide yes)
			)
		)
		(property "Description" ""
			(at 153.67 58.42 0)
			(effects
				(font
					(size 1.27 1.27)
				)
				(hide yes)
			)
		)
		(property "Author" "Antmicro"
			(at 162.56 66.04 0)
			(effects
				(font
					(size 1.27 1.27)
					(thickness 0.15)
				)
				(justify left bottom)
				(hide yes)
			)
		)
		(property "License" "Apache-2.0"
			(at 162.56 68.58 0)
			(effects
				(font
					(size 1.27 1.27)
					(thickness 0.15)
				)
				(justify left bottom)
				(hide yes)
			)
		)
		(pin "1"
		)
		(instances
			(project "thunderbolt-gpu-adapter"
				(path ""
					(reference "#PWR0218")
					(unit 1)
				)
			)
		)
	)
	(symbol
		(lib_id "antmicropower:GND")
		(at 123.19 259.08 0)
		(mirror y)
		(unit 1)
		(exclude_from_sim no)
		(in_bom yes)
		(on_board yes)
		(dnp no)
		(property "Reference" "#PWR0234"
			(at 123.19 265.43 0)
			(effects
				(font
					(size 1.27 1.27)
				)
				(hide yes)
			)
		)
		(property "Value" "GND"
			(at 125.095 263.525 0)
			(effects
				(font
					(size 1.27 1.27)
					(thickness 0.15)
				)
				(justify left bottom)
			)
		)
		(property "Footprint" ""
			(at 123.19 259.08 0)
			(effects
				(font
					(size 1.27 1.27)
					(thickness 0.15)
				)
				(justify left bottom)
				(hide yes)
			)
		)
		(property "Datasheet" ""
			(at 123.19 259.08 0)
			(effects
				(font
					(size 1.27 1.27)
					(thickness 0.15)
				)
				(justify left bottom)
				(hide yes)
			)
		)
		(property "Description" ""
			(at 123.19 259.08 0)
			(effects
				(font
					(size 1.27 1.27)
				)
				(hide yes)
			)
		)
		(property "Author" "Antmicro"
			(at 114.3 266.7 0)
			(effects
				(font
					(size 1.27 1.27)
					(thickness 0.15)
				)
				(justify left bottom)
				(hide yes)
			)
		)
		(property "License" "Apache-2.0"
			(at 114.3 269.24 0)
			(effects
				(font
					(size 1.27 1.27)
					(thickness 0.15)
				)
				(justify left bottom)
				(hide yes)
			)
		)
		(pin "1"
		)
		(instances
			(project "thunderbolt-gpu-adapter"
				(path ""
					(reference "#PWR0234")
					(unit 1)
				)
			)
		)
	)
	(symbol
		(lib_id "antmicropower:PWR_FLAG")
		(at 130.81 196.85 0)
		(unit 1)
		(exclude_from_sim no)
		(in_bom yes)
		(on_board yes)
		(dnp no)
		(property "Reference" "#FLG01"
			(at 130.81 194.945 0)
			(effects
				(font
					(size 1.27 1.27)
				)
				(hide yes)
			)
		)
		(property "Value" "PWR_FLAG"
			(at 130.81 193.04 0)
			(effects
				(font
					(size 1.27 1.27)
				)
			)
		)
		(property "Footprint" ""
			(at 130.81 196.85 0)
			(effects
				(font
					(size 1.27 1.27)
				)
				(hide yes)
			)
		)
		(property "Datasheet" ""
			(at 130.81 196.85 0)
			(effects
				(font
					(size 1.27 1.27)
				)
				(hide yes)
			)
		)
		(property "Description" ""
			(at 130.81 196.85 0)
			(effects
				(font
					(size 1.27 1.27)
				)
				(hide yes)
			)
		)
		(pin "1"
		)
		(instances
			(project "thunderbolt-gpu-adapter"
				(path ""
					(reference "#FLG01")
					(unit 1)
				)
			)
		)
	)
	(symbol
		(lib_id "antmicroCapacitors0603:C_22u_16V_0603")
		(at 194.31 210.82 90)
		(unit 1)
		(exclude_from_sim no)
		(in_bom yes)
		(on_board yes)
		(dnp no)
		(fields_autoplaced yes)
		(property "Reference" "C38"
			(at 196.85 207.0036 90)
			(effects
				(font
					(size 1.27 1.27)
					(thickness 0.15)
				)
				(justify right)
			)
		)
		(property "Value" "C_22u_16V_0603"
			(at 204.47 190.5 0)
			(effects
				(font
					(size 1.27 1.27)
					(thickness 0.15)
				)
				(justify left bottom)
				(hide yes)
			)
		)
		(property "Footprint" "antmicro-footprints:C_0603_1608Metric"
			(at 207.01 190.5 0)
			(effects
				(font
					(size 1.27 1.27)
					(thickness 0.15)
				)
				(justify left bottom)
				(hide yes)
			)
		)
		(property "Datasheet" "https://product.samsungsem.com/mlcc/CL10A226MO7JZN.do"
			(at 209.55 190.5 0)
			(effects
				(font
					(size 1.27 1.27)
					(thickness 0.15)
				)
				(justify left bottom)
				(hide yes)
			)
		)
		(property "Description" ""
			(at 194.31 210.82 0)
			(effects
				(font
					(size 1.27 1.27)
				)
				(hide yes)
			)
		)
		(property "MPN" "CL10A226MO7JZNC"
			(at 212.09 190.5 0)
			(effects
				(font
					(size 1.27 1.27)
					(thickness 0.15)
				)
				(justify left bottom)
				(hide yes)
			)
		)
		(property "Manufacturer" "Samsung Electro-Mechanics"
			(at 214.63 190.5 0)
			(effects
				(font
					(size 1.27 1.27)
					(thickness 0.15)
				)
				(justify left bottom)
				(hide yes)
			)
		)
		(property "License" "Apache-2.0"
			(at 217.17 190.5 0)
			(effects
				(font
					(size 1.27 1.27)
					(thickness 0.15)
				)
				(justify left bottom)
				(hide yes)
			)
		)
		(property "Val" "22u"
			(at 196.85 209.5436 90)
			(effects
				(font
					(size 1.27 1.27)
					(thickness 0.15)
				)
				(justify right)
			)
		)
		(property "Voltage" "16V"
			(at 222.25 190.5 0)
			(effects
				(font
					(size 1.27 1.27)
				)
				(justify left bottom)
				(hide yes)
			)
		)
		(property "Dielectric" ""
			(at 224.79 190.5 0)
			(effects
				(font
					(size 1.27 1.27)
				)
				(justify left bottom)
				(hide yes)
			)
		)
		(property "Author" "Antmicro"
			(at 219.71 190.5 0)
			(effects
				(font
					(size 1.27 1.27)
					(thickness 0.15)
				)
				(justify left bottom)
				(hide yes)
			)
		)
		(pin "1"
		)
		(pin "2"
		)
		(instances
			(project "thunderbolt-gpu-adapter"
				(path ""
					(reference "C38")
					(unit 1)
				)
			)
		)
	)
	(symbol
		(lib_id "antmicroResistors0402:R_100k_0402")
		(at 135.89 128.27 0)
		(unit 1)
		(exclude_from_sim no)
		(in_bom yes)
		(on_board yes)
		(dnp no)
		(property "Reference" "R30"
			(at 133.985 127 0)
			(effects
				(font
					(size 1.27 1.27)
					(thickness 0.15)
				)
			)
		)
		(property "Value" "R_100k_0402"
			(at 156.21 140.97 0)
			(effects
				(font
					(size 1.27 1.27)
					(thickness 0.15)
				)
				(justify left bottom)
				(hide yes)
			)
		)
		(property "Footprint" "antmicro-footprints:R_0402_1005Metric"
			(at 156.21 143.51 0)
			(effects
				(font
					(size 1.27 1.27)
					(thickness 0.15)
				)
				(justify left bottom)
				(hide yes)
			)
		)
		(property "Datasheet" "https://www.bourns.com/docs/product-datasheets/cr.pdf"
			(at 156.21 146.05 0)
			(effects
				(font
					(size 1.27 1.27)
					(thickness 0.15)
				)
				(justify left bottom)
				(hide yes)
			)
		)
		(property "Description" ""
			(at 135.89 128.27 0)
			(effects
				(font
					(size 1.27 1.27)
				)
				(hide yes)
			)
		)
		(property "MPN" "CR0402-FX-1003GLF"
			(at 156.21 148.59 0)
			(effects
				(font
					(size 1.27 1.27)
					(thickness 0.15)
				)
				(justify left bottom)
				(hide yes)
			)
		)
		(property "Manufacturer" "Bourns"
			(at 156.21 151.13 0)
			(effects
				(font
					(size 1.27 1.27)
					(thickness 0.15)
				)
				(justify left bottom)
				(hide yes)
			)
		)
		(property "License" "Apache-2.0"
			(at 156.21 153.67 0)
			(effects
				(font
					(size 1.27 1.27)
					(thickness 0.15)
				)
				(justify left bottom)
				(hide yes)
			)
		)
		(property "Val" "100k"
			(at 142.875 127 0)
			(effects
				(font
					(size 1.27 1.27)
					(thickness 0.15)
				)
			)
		)
		(property "Tolerance" "1%"
			(at 156.21 138.43 0)
			(effects
				(font
					(size 1.27 1.27)
				)
				(justify left bottom)
				(hide yes)
			)
		)
		(property "Author" "Antmicro"
			(at 156.21 156.21 0)
			(effects
				(font
					(size 1.27 1.27)
					(thickness 0.15)
				)
				(justify left bottom)
				(hide yes)
			)
		)
		(pin "1"
		)
		(pin "2"
		)
		(instances
			(project "thunderbolt-gpu-adapter"
				(path ""
					(reference "R30")
					(unit 1)
				)
			)
		)
	)
	(symbol
		(lib_id "antmicropower:GND")
		(at 83.82 394.97 0)
		(unit 1)
		(exclude_from_sim no)
		(in_bom yes)
		(on_board yes)
		(dnp no)
		(property "Reference" "#PWR0193"
			(at 83.82 401.32 0)
			(effects
				(font
					(size 1.27 1.27)
				)
				(hide yes)
			)
		)
		(property "Value" "GND"
			(at 83.82 398.78 0)
			(effects
				(font
					(size 1.27 1.27)
				)
			)
		)
		(property "Footprint" ""
			(at 83.82 394.97 0)
			(effects
				(font
					(size 1.27 1.27)
				)
				(hide yes)
			)
		)
		(property "Datasheet" ""
			(at 83.82 394.97 0)
			(effects
				(font
					(size 1.27 1.27)
				)
				(hide yes)
			)
		)
		(property "Description" ""
			(at 83.82 394.97 0)
			(effects
				(font
					(size 1.27 1.27)
				)
				(hide yes)
			)
		)
		(property "Author" "Antmicro"
			(at 92.71 402.59 0)
			(effects
				(font
					(size 1.27 1.27)
					(thickness 0.15)
				)
				(justify left bottom)
				(hide yes)
			)
		)
		(property "License" "Apache-2.0"
			(at 92.71 405.13 0)
			(effects
				(font
					(size 1.27 1.27)
					(thickness 0.15)
				)
				(justify left bottom)
				(hide yes)
			)
		)
		(pin "1"
		)
		(instances
			(project "thunderbolt-gpu-adapter"
				(path ""
					(reference "#PWR0193")
					(unit 1)
				)
			)
		)
	)
	(symbol
		(lib_id "antmicropower:GND")
		(at 213.36 287.02 0)
		(unit 1)
		(exclude_from_sim no)
		(in_bom yes)
		(on_board yes)
		(dnp no)
		(property "Reference" "#PWR0197"
			(at 213.36 293.37 0)
			(effects
				(font
					(size 1.27 1.27)
				)
				(hide yes)
			)
		)
		(property "Value" "GND"
			(at 213.36 290.83 0)
			(effects
				(font
					(size 1.27 1.27)
				)
			)
		)
		(property "Footprint" ""
			(at 213.36 287.02 0)
			(effects
				(font
					(size 1.27 1.27)
				)
				(hide yes)
			)
		)
		(property "Datasheet" ""
			(at 213.36 287.02 0)
			(effects
				(font
					(size 1.27 1.27)
				)
				(hide yes)
			)
		)
		(property "Description" ""
			(at 213.36 287.02 0)
			(effects
				(font
					(size 1.27 1.27)
				)
				(hide yes)
			)
		)
		(property "Author" "Antmicro"
			(at 222.25 294.64 0)
			(effects
				(font
					(size 1.27 1.27)
					(thickness 0.15)
				)
				(justify left bottom)
				(hide yes)
			)
		)
		(property "License" "Apache-2.0"
			(at 222.25 297.18 0)
			(effects
				(font
					(size 1.27 1.27)
					(thickness 0.15)
				)
				(justify left bottom)
				(hide yes)
			)
		)
		(pin "1"
		)
		(instances
			(project "thunderbolt-gpu-adapter"
				(path ""
					(reference "#PWR0197")
					(unit 1)
				)
			)
		)
	)
	(symbol
		(lib_id "antmicropower:GND")
		(at 194.31 212.09 0)
		(unit 1)
		(exclude_from_sim no)
		(in_bom yes)
		(on_board yes)
		(dnp no)
		(property "Reference" "#PWR0240"
			(at 194.31 218.44 0)
			(effects
				(font
					(size 1.27 1.27)
				)
				(hide yes)
			)
		)
		(property "Value" "GND"
			(at 192.405 216.535 0)
			(effects
				(font
					(size 1.27 1.27)
					(thickness 0.15)
				)
				(justify left bottom)
			)
		)
		(property "Footprint" ""
			(at 194.31 212.09 0)
			(effects
				(font
					(size 1.27 1.27)
					(thickness 0.15)
				)
				(justify left bottom)
				(hide yes)
			)
		)
		(property "Datasheet" ""
			(at 194.31 212.09 0)
			(effects
				(font
					(size 1.27 1.27)
					(thickness 0.15)
				)
				(justify left bottom)
				(hide yes)
			)
		)
		(property "Description" ""
			(at 194.31 212.09 0)
			(effects
				(font
					(size 1.27 1.27)
				)
				(hide yes)
			)
		)
		(property "Author" "Antmicro"
			(at 203.2 219.71 0)
			(effects
				(font
					(size 1.27 1.27)
					(thickness 0.15)
				)
				(justify left bottom)
				(hide yes)
			)
		)
		(property "License" "Apache-2.0"
			(at 203.2 222.25 0)
			(effects
				(font
					(size 1.27 1.27)
					(thickness 0.15)
				)
				(justify left bottom)
				(hide yes)
			)
		)
		(pin "1"
		)
		(instances
			(project "thunderbolt-gpu-adapter"
				(path ""
					(reference "#PWR0240")
					(unit 1)
				)
			)
		)
	)
	(symbol
		(lib_id "antmicropower:GND")
		(at 55.88 207.01 0)
		(unit 1)
		(exclude_from_sim no)
		(in_bom yes)
		(on_board yes)
		(dnp no)
		(property "Reference" "#PWR0215"
			(at 55.88 213.36 0)
			(effects
				(font
					(size 1.27 1.27)
				)
				(hide yes)
			)
		)
		(property "Value" "GND"
			(at 53.975 211.455 0)
			(effects
				(font
					(size 1.27 1.27)
					(thickness 0.15)
				)
				(justify left bottom)
			)
		)
		(property "Footprint" ""
			(at 55.88 207.01 0)
			(effects
				(font
					(size 1.27 1.27)
					(thickness 0.15)
				)
				(justify left bottom)
				(hide yes)
			)
		)
		(property "Datasheet" ""
			(at 55.88 207.01 0)
			(effects
				(font
					(size 1.27 1.27)
					(thickness 0.15)
				)
				(justify left bottom)
				(hide yes)
			)
		)
		(property "Description" ""
			(at 55.88 207.01 0)
			(effects
				(font
					(size 1.27 1.27)
				)
				(hide yes)
			)
		)
		(property "Author" "Antmicro"
			(at 64.77 214.63 0)
			(effects
				(font
					(size 1.27 1.27)
					(thickness 0.15)
				)
				(justify left bottom)
				(hide yes)
			)
		)
		(property "License" "Apache-2.0"
			(at 64.77 217.17 0)
			(effects
				(font
					(size 1.27 1.27)
					(thickness 0.15)
				)
				(justify left bottom)
				(hide yes)
			)
		)
		(pin "1"
		)
		(instances
			(project "thunderbolt-gpu-adapter"
				(path ""
					(reference "#PWR0215")
					(unit 1)
				)
			)
		)
	)
	(symbol
		(lib_id "antmicroResistors0402:R_10k_0402")
		(at 96.52 212.09 90)
		(unit 1)
		(exclude_from_sim no)
		(in_bom yes)
		(on_board yes)
		(dnp no)
		(fields_autoplaced yes)
		(property "Reference" "R8"
			(at 99.06 208.28 90)
			(effects
				(font
					(size 1.27 1.27)
					(thickness 0.15)
				)
				(justify right)
			)
		)
		(property "Value" "R_10k_0402"
			(at 109.22 191.77 0)
			(effects
				(font
					(size 1.27 1.27)
					(thickness 0.15)
				)
				(justify left bottom)
				(hide yes)
			)
		)
		(property "Footprint" "antmicro-footprints:R_0402_1005Metric"
			(at 111.76 191.77 0)
			(effects
				(font
					(size 1.27 1.27)
					(thickness 0.15)
				)
				(justify left bottom)
				(hide yes)
			)
		)
		(property "Datasheet" "https://www.bourns.com/docs/product-datasheets/cr.pdf"
			(at 114.3 191.77 0)
			(effects
				(font
					(size 1.27 1.27)
					(thickness 0.15)
				)
				(justify left bottom)
				(hide yes)
			)
		)
		(property "Description" ""
			(at 96.52 212.09 0)
			(effects
				(font
					(size 1.27 1.27)
				)
				(hide yes)
			)
		)
		(property "MPN" "CR0402-FX-1002GLF"
			(at 116.84 191.77 0)
			(effects
				(font
					(size 1.27 1.27)
					(thickness 0.15)
				)
				(justify left bottom)
				(hide yes)
			)
		)
		(property "Manufacturer" "Bourns"
			(at 119.38 191.77 0)
			(effects
				(font
					(size 1.27 1.27)
					(thickness 0.15)
				)
				(justify left bottom)
				(hide yes)
			)
		)
		(property "License" "Apache-2.0"
			(at 121.92 191.77 0)
			(effects
				(font
					(size 1.27 1.27)
					(thickness 0.15)
				)
				(justify left bottom)
				(hide yes)
			)
		)
		(property "Val" "10k"
			(at 99.06 210.82 90)
			(effects
				(font
					(size 1.27 1.27)
					(thickness 0.15)
				)
				(justify right)
			)
		)
		(property "Tolerance" "1%"
			(at 106.68 191.77 0)
			(effects
				(font
					(size 1.27 1.27)
				)
				(justify left bottom)
				(hide yes)
			)
		)
		(property "Author" "Antmicro"
			(at 124.46 191.77 0)
			(effects
				(font
					(size 1.27 1.27)
					(thickness 0.15)
				)
				(justify left bottom)
				(hide yes)
			)
		)
		(pin "1"
		)
		(pin "2"
		)
		(instances
			(project "thunderbolt-gpu-adapter"
				(path ""
					(reference "R8")
					(unit 1)
				)
			)
		)
	)
	(symbol
		(lib_id "antmicroFerriteBeadsandChips:FB_30Z_8.5A_Murata-BLM21SN_0805")
		(at 187.96 46.99 0)
		(mirror x)
		(unit 1)
		(exclude_from_sim no)
		(in_bom yes)
		(on_board yes)
		(dnp no)
		(property "Reference" "FB8"
			(at 190.5 41.91 0)
			(effects
				(font
					(size 1.27 1.27)
					(thickness 0.15)
				)
			)
		)
		(property "Value" "FB_30Z_8.5A_Murata-BLM21SN_0805"
			(at 194.945 43.815 0)
			(effects
				(font
					(size 1.27 1.27)
					(thickness 0.15)
				)
				(hide yes)
			)
		)
		(property "Footprint" "antmicro-footprints:FB_0805_2012Metric"
			(at 201.93 41.91 0)
			(effects
				(font
					(size 1.27 1.27)
					(thickness 0.15)
				)
				(justify left bottom)
				(hide yes)
			)
		)
		(property "Datasheet" "https://www.murata.com/en-sg/products/productdata/8796738977822/ENFA0005.pdf?1519270210000"
			(at 201.93 39.37 0)
			(effects
				(font
					(size 1.27 1.27)
					(thickness 0.15)
				)
				(justify left bottom)
				(hide yes)
			)
		)
		(property "Description" ""
			(at 187.96 46.99 0)
			(effects
				(font
					(size 1.27 1.27)
				)
				(hide yes)
			)
		)
		(property "MPN" "BLM21SN300SZ1D"
			(at 201.93 36.83 0)
			(effects
				(font
					(size 1.27 1.27)
					(thickness 0.15)
				)
				(justify left bottom)
				(hide yes)
			)
		)
		(property "Manufacturer" "Murata"
			(at 201.93 34.29 0)
			(effects
				(font
					(size 1.27 1.27)
					(thickness 0.15)
				)
				(justify left bottom)
				(hide yes)
			)
		)
		(property "License" "Apache-2.0"
			(at 201.93 29.21 0)
			(effects
				(font
					(size 1.27 1.27)
					(thickness 0.15)
				)
				(justify left bottom)
				(hide yes)
			)
		)
		(property "Author" "Antmicro"
			(at 201.93 31.75 0)
			(effects
				(font
					(size 1.27 1.27)
					(thickness 0.15)
				)
				(justify left bottom)
				(hide yes)
			)
		)
		(property "Val" "30Z/8.5A"
			(at 185.42 43.18 0)
			(effects
				(font
					(size 1.27 1.27)
				)
				(justify left bottom)
			)
		)
		(property "Current" ""
			(at 208.28 24.13 0)
			(effects
				(font
					(size 1.27 1.27)
					(thickness 0.15)
				)
				(justify left bottom)
				(hide yes)
			)
		)
		(pin "1"
		)
		(pin "2"
		)
		(instances
			(project "thunderbolt-gpu-adapter"
				(path ""
					(reference "FB8")
					(unit 1)
				)
			)
		)
	)
	(symbol
		(lib_id "antmicropower:GND")
		(at 76.2 207.01 0)
		(unit 1)
		(exclude_from_sim no)
		(in_bom yes)
		(on_board yes)
		(dnp no)
		(property "Reference" "#PWR0228"
			(at 76.2 213.36 0)
			(effects
				(font
					(size 1.27 1.27)
				)
				(hide yes)
			)
		)
		(property "Value" "GND"
			(at 74.295 211.455 0)
			(effects
				(font
					(size 1.27 1.27)
					(thickness 0.15)
				)
				(justify left bottom)
			)
		)
		(property "Footprint" ""
			(at 76.2 207.01 0)
			(effects
				(font
					(size 1.27 1.27)
					(thickness 0.15)
				)
				(justify left bottom)
				(hide yes)
			)
		)
		(property "Datasheet" ""
			(at 76.2 207.01 0)
			(effects
				(font
					(size 1.27 1.27)
					(thickness 0.15)
				)
				(justify left bottom)
				(hide yes)
			)
		)
		(property "Description" ""
			(at 76.2 207.01 0)
			(effects
				(font
					(size 1.27 1.27)
				)
				(hide yes)
			)
		)
		(property "Author" "Antmicro"
			(at 85.09 214.63 0)
			(effects
				(font
					(size 1.27 1.27)
					(thickness 0.15)
				)
				(justify left bottom)
				(hide yes)
			)
		)
		(property "License" "Apache-2.0"
			(at 85.09 217.17 0)
			(effects
				(font
					(size 1.27 1.27)
					(thickness 0.15)
				)
				(justify left bottom)
				(hide yes)
			)
		)
		(pin "1"
		)
		(instances
			(project "thunderbolt-gpu-adapter"
				(path ""
					(reference "#PWR0228")
					(unit 1)
				)
			)
		)
	)
	(symbol
		(lib_id "antmicroCapacitors0402:C_100n_0402")
		(at 185.42 210.82 270)
		(mirror x)
		(unit 1)
		(exclude_from_sim no)
		(in_bom yes)
		(on_board yes)
		(dnp no)
		(fields_autoplaced yes)
		(property "Reference" "C32"
			(at 187.96 207.0036 90)
			(effects
				(font
					(size 1.27 1.27)
					(thickness 0.15)
				)
				(justify left)
			)
		)
		(property "Value" "C_100n_0402"
			(at 175.26 190.5 0)
			(effects
				(font
					(size 1.27 1.27)
					(thickness 0.15)
				)
				(justify left bottom)
				(hide yes)
			)
		)
		(property "Footprint" "antmicro-footprints:C_0402_1005Metric"
			(at 172.72 190.5 0)
			(effects
				(font
					(size 1.27 1.27)
					(thickness 0.15)
				)
				(justify left bottom)
				(hide yes)
			)
		)
		(property "Datasheet" "https://www.murata.com/products/productdetail?partno=GRM155R61H104KE14%23"
			(at 170.18 190.5 0)
			(effects
				(font
					(size 1.27 1.27)
					(thickness 0.15)
				)
				(justify left bottom)
				(hide yes)
			)
		)
		(property "Description" ""
			(at 185.42 210.82 0)
			(effects
				(font
					(size 1.27 1.27)
				)
				(hide yes)
			)
		)
		(property "MPN" "GRM155R61H104KE14D"
			(at 167.64 190.5 0)
			(effects
				(font
					(size 1.27 1.27)
					(thickness 0.15)
				)
				(justify left bottom)
				(hide yes)
			)
		)
		(property "Manufacturer" "Murata"
			(at 165.1 190.5 0)
			(effects
				(font
					(size 1.27 1.27)
					(thickness 0.15)
				)
				(justify left bottom)
				(hide yes)
			)
		)
		(property "License" "Apache-2.0"
			(at 162.56 190.5 0)
			(effects
				(font
					(size 1.27 1.27)
					(thickness 0.15)
				)
				(justify left bottom)
				(hide yes)
			)
		)
		(property "Val" "100n"
			(at 187.96 209.5436 90)
			(effects
				(font
					(size 1.27 1.27)
					(thickness 0.15)
				)
				(justify left)
			)
		)
		(property "Voltage" "50V"
			(at 157.48 190.5 0)
			(effects
				(font
					(size 1.27 1.27)
				)
				(justify left bottom)
				(hide yes)
			)
		)
		(property "Dielectric" "X5R"
			(at 154.94 190.5 0)
			(effects
				(font
					(size 1.27 1.27)
				)
				(justify left bottom)
				(hide yes)
			)
		)
		(property "Author" "Antmicro"
			(at 160.02 190.5 0)
			(effects
				(font
					(size 1.27 1.27)
					(thickness 0.15)
				)
				(justify left bottom)
				(hide yes)
			)
		)
		(pin "1"
		)
		(pin "2"
		)
		(instances
			(project "thunderbolt-gpu-adapter"
				(path ""
					(reference "C32")
					(unit 1)
				)
			)
		)
	)
	(symbol
		(lib_id "antmicropower:PWR_FLAG")
		(at 266.7 201.93 0)
		(unit 1)
		(exclude_from_sim no)
		(in_bom yes)
		(on_board yes)
		(dnp no)
		(property "Reference" "#FLG03"
			(at 266.7 200.025 0)
			(effects
				(font
					(size 1.27 1.27)
				)
				(hide yes)
			)
		)
		(property "Value" "PWR_FLAG"
			(at 266.7 198.12 0)
			(effects
				(font
					(size 1.27 1.27)
				)
			)
		)
		(property "Footprint" ""
			(at 266.7 201.93 0)
			(effects
				(font
					(size 1.27 1.27)
				)
				(hide yes)
			)
		)
		(property "Datasheet" ""
			(at 266.7 201.93 0)
			(effects
				(font
					(size 1.27 1.27)
				)
				(hide yes)
			)
		)
		(property "Description" ""
			(at 266.7 201.93 0)
			(effects
				(font
					(size 1.27 1.27)
				)
				(hide yes)
			)
		)
		(pin "1"
		)
		(instances
			(project "thunderbolt-gpu-adapter"
				(path ""
					(reference "#FLG03")
					(unit 1)
				)
			)
		)
	)
	(symbol
		(lib_id "antmicropower:GND")
		(at 66.04 252.73 0)
		(unit 1)
		(exclude_from_sim no)
		(in_bom yes)
		(on_board yes)
		(dnp no)
		(property "Reference" "#PWR0152"
			(at 66.04 259.08 0)
			(effects
				(font
					(size 1.27 1.27)
				)
				(hide yes)
			)
		)
		(property "Value" "GND"
			(at 66.04 256.54 0)
			(effects
				(font
					(size 1.27 1.27)
				)
			)
		)
		(property "Footprint" ""
			(at 66.04 252.73 0)
			(effects
				(font
					(size 1.27 1.27)
				)
				(hide yes)
			)
		)
		(property "Datasheet" ""
			(at 66.04 252.73 0)
			(effects
				(font
					(size 1.27 1.27)
				)
				(hide yes)
			)
		)
		(property "Description" ""
			(at 66.04 252.73 0)
			(effects
				(font
					(size 1.27 1.27)
				)
				(hide yes)
			)
		)
		(property "Author" "Antmicro"
			(at 74.93 260.35 0)
			(effects
				(font
					(size 1.27 1.27)
					(thickness 0.15)
				)
				(justify left bottom)
				(hide yes)
			)
		)
		(property "License" "Apache-2.0"
			(at 74.93 262.89 0)
			(effects
				(font
					(size 1.27 1.27)
					(thickness 0.15)
				)
				(justify left bottom)
				(hide yes)
			)
		)
		(pin "1"
		)
		(instances
			(project "thunderbolt-gpu-adapter"
				(path ""
					(reference "#PWR0152")
					(unit 1)
				)
			)
		)
	)
	(symbol
		(lib_id "antmicroResistors0402:R_10k_0402")
		(at 232.41 285.75 90)
		(unit 1)
		(exclude_from_sim no)
		(in_bom yes)
		(on_board yes)
		(dnp no)
		(fields_autoplaced yes)
		(property "Reference" "R93"
			(at 234.95 281.94 90)
			(effects
				(font
					(size 1.27 1.27)
					(thickness 0.15)
				)
				(justify right)
			)
		)
		(property "Value" "R_10k_0402"
			(at 245.11 265.43 0)
			(effects
				(font
					(size 1.27 1.27)
					(thickness 0.15)
				)
				(justify left bottom)
				(hide yes)
			)
		)
		(property "Footprint" "antmicro-footprints:R_0402_1005Metric"
			(at 247.65 265.43 0)
			(effects
				(font
					(size 1.27 1.27)
					(thickness 0.15)
				)
				(justify left bottom)
				(hide yes)
			)
		)
		(property "Datasheet" "https://www.bourns.com/docs/product-datasheets/cr.pdf"
			(at 250.19 265.43 0)
			(effects
				(font
					(size 1.27 1.27)
					(thickness 0.15)
				)
				(justify left bottom)
				(hide yes)
			)
		)
		(property "Description" ""
			(at 232.41 285.75 0)
			(effects
				(font
					(size 1.27 1.27)
				)
				(hide yes)
			)
		)
		(property "MPN" "CR0402-FX-1002GLF"
			(at 252.73 265.43 0)
			(effects
				(font
					(size 1.27 1.27)
					(thickness 0.15)
				)
				(justify left bottom)
				(hide yes)
			)
		)
		(property "Manufacturer" "Bourns"
			(at 255.27 265.43 0)
			(effects
				(font
					(size 1.27 1.27)
					(thickness 0.15)
				)
				(justify left bottom)
				(hide yes)
			)
		)
		(property "License" "Apache-2.0"
			(at 257.81 265.43 0)
			(effects
				(font
					(size 1.27 1.27)
					(thickness 0.15)
				)
				(justify left bottom)
				(hide yes)
			)
		)
		(property "Author" "Antmicro"
			(at 260.35 265.43 0)
			(effects
				(font
					(size 1.27 1.27)
					(thickness 0.15)
				)
				(justify left bottom)
				(hide yes)
			)
		)
		(property "Val" "10k"
			(at 234.95 284.48 90)
			(effects
				(font
					(size 1.27 1.27)
					(thickness 0.15)
				)
				(justify right)
			)
		)
		(property "Tolerance" "1%"
			(at 242.57 265.43 0)
			(effects
				(font
					(size 1.27 1.27)
				)
				(justify left bottom)
				(hide yes)
			)
		)
		(pin "1"
		)
		(pin "2"
		)
		(instances
			(project "thunderbolt-gpu-adapter"
				(path ""
					(reference "R93")
					(unit 1)
				)
			)
		)
	)
	(symbol
		(lib_id "antmicroTestPoints:TP_1mm_SMD")
		(at 127 226.06 0)
		(mirror y)
		(unit 1)
		(exclude_from_sim no)
		(in_bom no)
		(on_board yes)
		(dnp no)
		(property "Reference" "TP5"
			(at 119.38 226.06 0)
			(effects
				(font
					(size 1.27 1.27)
					(thickness 0.15)
				)
				(justify right)
			)
		)
		(property "Value" "TP_1mm_SMD"
			(at 111.76 233.68 0)
			(effects
				(font
					(size 1.27 1.27)
					(thickness 0.15)
				)
				(justify left bottom)
				(hide yes)
			)
		)
		(property "Footprint" "antmicro-footprints:TP_SMD_1mm"
			(at 111.76 236.22 0)
			(effects
				(font
					(size 1.27 1.27)
					(thickness 0.15)
				)
				(justify left bottom)
				(hide yes)
			)
		)
		(property "Datasheet" ""
			(at 109.22 238.76 0)
			(effects
				(font
					(size 1.27 1.27)
					(thickness 0.15)
				)
				(justify left bottom)
				(hide yes)
			)
		)
		(property "Description" ""
			(at 127 226.06 0)
			(effects
				(font
					(size 1.27 1.27)
				)
				(hide yes)
			)
		)
		(property "License" "Apache-2.0"
			(at 111.76 243.84 0)
			(effects
				(font
					(size 1.27 1.27)
					(thickness 0.15)
				)
				(justify left bottom)
				(hide yes)
			)
		)
		(property "Manufacturer" ""
			(at 127 226.06 0)
			(effects
				(font
					(size 1.27 1.27)
				)
				(hide yes)
			)
		)
		(property "MPN" ""
			(at 127 226.06 0)
			(effects
				(font
					(size 1.27 1.27)
				)
				(hide yes)
			)
		)
		(property "Author" "Antmicro"
			(at 111.76 241.3 0)
			(effects
				(font
					(size 1.27 1.27)
					(thickness 0.15)
				)
				(justify left bottom)
				(hide yes)
			)
		)
		(pin "1"
		)
		(instances
			(project "thunderbolt-gpu-adapter"
				(path ""
					(reference "TP5")
					(unit 1)
				)
			)
		)
	)
	(symbol
		(lib_id "antmicroResistors0402:R_100k_0402")
		(at 135.89 148.59 0)
		(unit 1)
		(exclude_from_sim no)
		(in_bom yes)
		(on_board yes)
		(dnp no)
		(property "Reference" "R33"
			(at 133.985 147.32 0)
			(effects
				(font
					(size 1.27 1.27)
					(thickness 0.15)
				)
			)
		)
		(property "Value" "R_100k_0402"
			(at 156.21 161.29 0)
			(effects
				(font
					(size 1.27 1.27)
					(thickness 0.15)
				)
				(justify left bottom)
				(hide yes)
			)
		)
		(property "Footprint" "antmicro-footprints:R_0402_1005Metric"
			(at 156.21 163.83 0)
			(effects
				(font
					(size 1.27 1.27)
					(thickness 0.15)
				)
				(justify left bottom)
				(hide yes)
			)
		)
		(property "Datasheet" "https://www.bourns.com/docs/product-datasheets/cr.pdf"
			(at 156.21 166.37 0)
			(effects
				(font
					(size 1.27 1.27)
					(thickness 0.15)
				)
				(justify left bottom)
				(hide yes)
			)
		)
		(property "Description" ""
			(at 135.89 148.59 0)
			(effects
				(font
					(size 1.27 1.27)
				)
				(hide yes)
			)
		)
		(property "MPN" "CR0402-FX-1003GLF"
			(at 156.21 168.91 0)
			(effects
				(font
					(size 1.27 1.27)
					(thickness 0.15)
				)
				(justify left bottom)
				(hide yes)
			)
		)
		(property "Manufacturer" "Bourns"
			(at 156.21 171.45 0)
			(effects
				(font
					(size 1.27 1.27)
					(thickness 0.15)
				)
				(justify left bottom)
				(hide yes)
			)
		)
		(property "License" "Apache-2.0"
			(at 156.21 173.99 0)
			(effects
				(font
					(size 1.27 1.27)
					(thickness 0.15)
				)
				(justify left bottom)
				(hide yes)
			)
		)
		(property "Val" "100k"
			(at 142.875 147.32 0)
			(effects
				(font
					(size 1.27 1.27)
					(thickness 0.15)
				)
			)
		)
		(property "Tolerance" "1%"
			(at 156.21 158.75 0)
			(effects
				(font
					(size 1.27 1.27)
				)
				(justify left bottom)
				(hide yes)
			)
		)
		(property "Author" "Antmicro"
			(at 156.21 176.53 0)
			(effects
				(font
					(size 1.27 1.27)
					(thickness 0.15)
				)
				(justify left bottom)
				(hide yes)
			)
		)
		(pin "1"
		)
		(pin "2"
		)
		(instances
			(project "thunderbolt-gpu-adapter"
				(path ""
					(reference "R33")
					(unit 1)
				)
			)
		)
	)
	(symbol
		(lib_id "antmicropower:GND")
		(at 231.14 326.39 0)
		(unit 1)
		(exclude_from_sim no)
		(in_bom yes)
		(on_board yes)
		(dnp no)
		(property "Reference" "#PWR0157"
			(at 231.14 332.74 0)
			(effects
				(font
					(size 1.27 1.27)
				)
				(hide yes)
			)
		)
		(property "Value" "GND"
			(at 231.14 330.2 0)
			(effects
				(font
					(size 1.27 1.27)
				)
			)
		)
		(property "Footprint" ""
			(at 231.14 326.39 0)
			(effects
				(font
					(size 1.27 1.27)
				)
				(hide yes)
			)
		)
		(property "Datasheet" ""
			(at 231.14 326.39 0)
			(effects
				(font
					(size 1.27 1.27)
				)
				(hide yes)
			)
		)
		(property "Description" ""
			(at 231.14 326.39 0)
			(effects
				(font
					(size 1.27 1.27)
				)
				(hide yes)
			)
		)
		(property "Author" "Antmicro"
			(at 240.03 334.01 0)
			(effects
				(font
					(size 1.27 1.27)
					(thickness 0.15)
				)
				(justify left bottom)
				(hide yes)
			)
		)
		(property "License" "Apache-2.0"
			(at 240.03 336.55 0)
			(effects
				(font
					(size 1.27 1.27)
					(thickness 0.15)
				)
				(justify left bottom)
				(hide yes)
			)
		)
		(pin "1"
		)
		(instances
			(project "thunderbolt-gpu-adapter"
				(path ""
					(reference "#PWR0157")
					(unit 1)
				)
			)
		)
	)
	(symbol
		(lib_id "antmicroResistors0402:R_330R_0402")
		(at 199.39 363.22 90)
		(unit 1)
		(exclude_from_sim no)
		(in_bom yes)
		(on_board yes)
		(dnp no)
		(fields_autoplaced yes)
		(property "Reference" "R42"
			(at 201.93 359.41 90)
			(effects
				(font
					(size 1.27 1.27)
					(thickness 0.15)
				)
				(justify right)
			)
		)
		(property "Value" "R_330R_0402"
			(at 212.09 342.9 0)
			(effects
				(font
					(size 1.27 1.27)
					(thickness 0.15)
				)
				(justify left bottom)
				(hide yes)
			)
		)
		(property "Footprint" "antmicro-footprints:R_0402_1005Metric"
			(at 214.63 342.9 0)
			(effects
				(font
					(size 1.27 1.27)
					(thickness 0.15)
				)
				(justify left bottom)
				(hide yes)
			)
		)
		(property "Datasheet" "https://www.bourns.com/docs/product-datasheets/cr.pdf"
			(at 217.17 342.9 0)
			(effects
				(font
					(size 1.27 1.27)
					(thickness 0.15)
				)
				(justify left bottom)
				(hide yes)
			)
		)
		(property "Description" ""
			(at 199.39 363.22 0)
			(effects
				(font
					(size 1.27 1.27)
				)
				(hide yes)
			)
		)
		(property "MPN" "CR0402-FX-3300GLF"
			(at 219.71 342.9 0)
			(effects
				(font
					(size 1.27 1.27)
					(thickness 0.15)
				)
				(justify left bottom)
				(hide yes)
			)
		)
		(property "Manufacturer" "Bourns"
			(at 222.25 342.9 0)
			(effects
				(font
					(size 1.27 1.27)
					(thickness 0.15)
				)
				(justify left bottom)
				(hide yes)
			)
		)
		(property "License" "Apache-2.0"
			(at 224.79 342.9 0)
			(effects
				(font
					(size 1.27 1.27)
					(thickness 0.15)
				)
				(justify left bottom)
				(hide yes)
			)
		)
		(property "Val" "330R"
			(at 201.93 361.95 90)
			(effects
				(font
					(size 1.27 1.27)
					(thickness 0.15)
				)
				(justify right)
			)
		)
		(property "Tolerance" "1%"
			(at 209.55 342.9 0)
			(effects
				(font
					(size 1.27 1.27)
				)
				(justify left bottom)
				(hide yes)
			)
		)
		(property "Author" "Antmicro"
			(at 227.33 342.9 0)
			(effects
				(font
					(size 1.27 1.27)
					(thickness 0.15)
				)
				(justify left bottom)
				(hide yes)
			)
		)
		(pin "1"
		)
		(pin "2"
		)
		(instances
			(project "thunderbolt-gpu-adapter"
				(path ""
					(reference "R42")
					(unit 1)
				)
			)
		)
	)
	(symbol
		(lib_id "antmicroResistors0402:R_10k_0402")
		(at 49.53 242.57 0)
		(unit 1)
		(exclude_from_sim no)
		(in_bom yes)
		(on_board yes)
		(dnp no)
		(fields_autoplaced yes)
		(property "Reference" "R91"
			(at 52.07 236.22 0)
			(effects
				(font
					(size 1.27 1.27)
					(thickness 0.15)
				)
			)
		)
		(property "Value" "R_10k_0402"
			(at 69.85 255.27 0)
			(effects
				(font
					(size 1.27 1.27)
					(thickness 0.15)
				)
				(justify left bottom)
				(hide yes)
			)
		)
		(property "Footprint" "antmicro-footprints:R_0402_1005Metric"
			(at 69.85 257.81 0)
			(effects
				(font
					(size 1.27 1.27)
					(thickness 0.15)
				)
				(justify left bottom)
				(hide yes)
			)
		)
		(property "Datasheet" "https://www.bourns.com/docs/product-datasheets/cr.pdf"
			(at 69.85 260.35 0)
			(effects
				(font
					(size 1.27 1.27)
					(thickness 0.15)
				)
				(justify left bottom)
				(hide yes)
			)
		)
		(property "Description" ""
			(at 49.53 242.57 0)
			(effects
				(font
					(size 1.27 1.27)
				)
				(hide yes)
			)
		)
		(property "MPN" "CR0402-FX-1002GLF"
			(at 69.85 262.89 0)
			(effects
				(font
					(size 1.27 1.27)
					(thickness 0.15)
				)
				(justify left bottom)
				(hide yes)
			)
		)
		(property "Manufacturer" "Bourns"
			(at 69.85 265.43 0)
			(effects
				(font
					(size 1.27 1.27)
					(thickness 0.15)
				)
				(justify left bottom)
				(hide yes)
			)
		)
		(property "License" "Apache-2.0"
			(at 69.85 267.97 0)
			(effects
				(font
					(size 1.27 1.27)
					(thickness 0.15)
				)
				(justify left bottom)
				(hide yes)
			)
		)
		(property "Val" "10k"
			(at 52.07 238.76 0)
			(effects
				(font
					(size 1.27 1.27)
					(thickness 0.15)
				)
			)
		)
		(property "Tolerance" "1%"
			(at 69.85 252.73 0)
			(effects
				(font
					(size 1.27 1.27)
				)
				(justify left bottom)
				(hide yes)
			)
		)
		(property "Author" "Antmicro"
			(at 69.85 270.51 0)
			(effects
				(font
					(size 1.27 1.27)
					(thickness 0.15)
				)
				(justify left bottom)
				(hide yes)
			)
		)
		(pin "1"
		)
		(pin "2"
		)
		(instances
			(project "thunderbolt-gpu-adapter"
				(path ""
					(reference "R91")
					(unit 1)
				)
			)
		)
	)
	(symbol
		(lib_id "antmicroFerriteBeadsandChips:FB_30Z_8.5A_Murata-BLM21SN_0805")
		(at 99.06 384.81 0)
		(mirror x)
		(unit 1)
		(exclude_from_sim no)
		(in_bom yes)
		(on_board yes)
		(dnp no)
		(property "Reference" "FB6"
			(at 101.6 379.095 0)
			(effects
				(font
					(size 1.27 1.27)
					(thickness 0.15)
				)
			)
		)
		(property "Value" "FB_30Z_8.5A_Murata-BLM21SN_0805"
			(at 100.965 381.635 0)
			(effects
				(font
					(size 1.27 1.27)
					(thickness 0.15)
				)
				(hide yes)
			)
		)
		(property "Footprint" "antmicro-footprints:FB_0805_2012Metric"
			(at 113.03 379.73 0)
			(effects
				(font
					(size 1.27 1.27)
					(thickness 0.15)
				)
				(justify left bottom)
				(hide yes)
			)
		)
		(property "Datasheet" "https://www.murata.com/en-sg/products/productdata/8796738977822/ENFA0005.pdf?1519270210000"
			(at 113.03 377.19 0)
			(effects
				(font
					(size 1.27 1.27)
					(thickness 0.15)
				)
				(justify left bottom)
				(hide yes)
			)
		)
		(property "Description" ""
			(at 99.06 384.81 0)
			(effects
				(font
					(size 1.27 1.27)
				)
				(hide yes)
			)
		)
		(property "MPN" "BLM21SN300SZ1D"
			(at 113.03 374.65 0)
			(effects
				(font
					(size 1.27 1.27)
					(thickness 0.15)
				)
				(justify left bottom)
				(hide yes)
			)
		)
		(property "Manufacturer" "Murata"
			(at 113.03 372.11 0)
			(effects
				(font
					(size 1.27 1.27)
					(thickness 0.15)
				)
				(justify left bottom)
				(hide yes)
			)
		)
		(property "License" "Apache-2.0"
			(at 113.03 367.03 0)
			(effects
				(font
					(size 1.27 1.27)
					(thickness 0.15)
				)
				(justify left bottom)
				(hide yes)
			)
		)
		(property "Author" "Antmicro"
			(at 113.03 369.57 0)
			(effects
				(font
					(size 1.27 1.27)
					(thickness 0.15)
				)
				(justify left bottom)
				(hide yes)
			)
		)
		(property "Val" "30Z/8.5A"
			(at 96.52 381 0)
			(effects
				(font
					(size 1.27 1.27)
				)
				(justify left bottom)
			)
		)
		(property "Current" ""
			(at 119.38 361.95 0)
			(effects
				(font
					(size 1.27 1.27)
					(thickness 0.15)
				)
				(justify left bottom)
				(hide yes)
			)
		)
		(pin "1"
		)
		(pin "2"
		)
		(instances
			(project "thunderbolt-gpu-adapter"
				(path ""
					(reference "FB6")
					(unit 1)
				)
			)
		)
	)
	(symbol
		(lib_id "antmicroCapacitors0402:C_1u_0402")
		(at 196.85 119.38 90)
		(unit 1)
		(exclude_from_sim no)
		(in_bom yes)
		(on_board yes)
		(dnp no)
		(property "Reference" "C131"
			(at 198.755 115.57 90)
			(effects
				(font
					(size 1.27 1.27)
					(thickness 0.15)
				)
				(justify right)
			)
		)
		(property "Value" "C_1u_0402"
			(at 207.01 99.06 0)
			(effects
				(font
					(size 1.27 1.27)
					(thickness 0.15)
				)
				(justify left bottom)
				(hide yes)
			)
		)
		(property "Footprint" "antmicro-footprints:C_0402_1005Metric"
			(at 209.55 99.06 0)
			(effects
				(font
					(size 1.27 1.27)
					(thickness 0.15)
				)
				(justify left bottom)
				(hide yes)
			)
		)
		(property "Datasheet" "https://product.tdk.com/en/search/capacitor/ceramic/mlcc/info?part_no=C1005X6S1A105K050BC"
			(at 212.09 99.06 0)
			(effects
				(font
					(size 1.27 1.27)
					(thickness 0.15)
				)
				(justify left bottom)
				(hide yes)
			)
		)
		(property "Description" ""
			(at 196.85 119.38 0)
			(effects
				(font
					(size 1.27 1.27)
				)
				(hide yes)
			)
		)
		(property "MPN" "C1005X6S1A105K050BC"
			(at 214.63 99.06 0)
			(effects
				(font
					(size 1.27 1.27)
					(thickness 0.15)
				)
				(justify left bottom)
				(hide yes)
			)
		)
		(property "Manufacturer" "TDK"
			(at 217.17 99.06 0)
			(effects
				(font
					(size 1.27 1.27)
					(thickness 0.15)
				)
				(justify left bottom)
				(hide yes)
			)
		)
		(property "License" "Apache-2.0"
			(at 219.71 99.06 0)
			(effects
				(font
					(size 1.27 1.27)
					(thickness 0.15)
				)
				(justify left bottom)
				(hide yes)
			)
		)
		(property "Author" "Antmicro"
			(at 222.25 99.06 0)
			(effects
				(font
					(size 1.27 1.27)
					(thickness 0.15)
				)
				(justify left bottom)
				(hide yes)
			)
		)
		(property "Val" "1u"
			(at 198.755 118.11 90)
			(effects
				(font
					(size 1.27 1.27)
					(thickness 0.15)
				)
				(justify right)
			)
		)
		(property "Voltage" ""
			(at 224.79 99.06 0)
			(effects
				(font
					(size 1.27 1.27)
				)
				(justify left bottom)
				(hide yes)
			)
		)
		(property "Dielectric" ""
			(at 227.33 99.06 0)
			(effects
				(font
					(size 1.27 1.27)
				)
				(justify left bottom)
				(hide yes)
			)
		)
		(pin "1"
		)
		(pin "2"
		)
		(instances
			(project "thunderbolt-gpu-adapter"
				(path ""
					(reference "C131")
					(unit 1)
				)
			)
		)
	)
	(symbol
		(lib_id "antmicropower:GND")
		(at 185.42 212.09 0)
		(unit 1)
		(exclude_from_sim no)
		(in_bom yes)
		(on_board yes)
		(dnp no)
		(property "Reference" "#PWR0239"
			(at 185.42 218.44 0)
			(effects
				(font
					(size 1.27 1.27)
				)
				(hide yes)
			)
		)
		(property "Value" "GND"
			(at 183.515 216.535 0)
			(effects
				(font
					(size 1.27 1.27)
					(thickness 0.15)
				)
				(justify left bottom)
			)
		)
		(property "Footprint" ""
			(at 185.42 212.09 0)
			(effects
				(font
					(size 1.27 1.27)
					(thickness 0.15)
				)
				(justify left bottom)
				(hide yes)
			)
		)
		(property "Datasheet" ""
			(at 185.42 212.09 0)
			(effects
				(font
					(size 1.27 1.27)
					(thickness 0.15)
				)
				(justify left bottom)
				(hide yes)
			)
		)
		(property "Description" ""
			(at 185.42 212.09 0)
			(effects
				(font
					(size 1.27 1.27)
				)
				(hide yes)
			)
		)
		(property "Author" "Antmicro"
			(at 194.31 219.71 0)
			(effects
				(font
					(size 1.27 1.27)
					(thickness 0.15)
				)
				(justify left bottom)
				(hide yes)
			)
		)
		(property "License" "Apache-2.0"
			(at 194.31 222.25 0)
			(effects
				(font
					(size 1.27 1.27)
					(thickness 0.15)
				)
				(justify left bottom)
				(hide yes)
			)
		)
		(pin "1"
		)
		(instances
			(project "thunderbolt-gpu-adapter"
				(path ""
					(reference "#PWR0239")
					(unit 1)
				)
			)
		)
	)
	(symbol
		(lib_id "antmicroResistors0402:R_100k_0402")
		(at 128.27 212.09 270)
		(unit 1)
		(exclude_from_sim no)
		(in_bom yes)
		(on_board yes)
		(dnp no)
		(fields_autoplaced yes)
		(property "Reference" "R22"
			(at 125.73 213.36 90)
			(effects
				(font
					(size 1.27 1.27)
					(thickness 0.15)
				)
				(justify right)
			)
		)
		(property "Value" "R_100k_0402"
			(at 115.57 232.41 0)
			(effects
				(font
					(size 1.27 1.27)
					(thickness 0.15)
				)
				(justify left bottom)
				(hide yes)
			)
		)
		(property "Footprint" "antmicro-footprints:R_0402_1005Metric"
			(at 113.03 232.41 0)
			(effects
				(font
					(size 1.27 1.27)
					(thickness 0.15)
				)
				(justify left bottom)
				(hide yes)
			)
		)
		(property "Datasheet" "https://www.bourns.com/docs/product-datasheets/cr.pdf"
			(at 110.49 232.41 0)
			(effects
				(font
					(size 1.27 1.27)
					(thickness 0.15)
				)
				(justify left bottom)
				(hide yes)
			)
		)
		(property "Description" ""
			(at 128.27 212.09 0)
			(effects
				(font
					(size 1.27 1.27)
				)
				(hide yes)
			)
		)
		(property "MPN" "CR0402-FX-1003GLF"
			(at 107.95 232.41 0)
			(effects
				(font
					(size 1.27 1.27)
					(thickness 0.15)
				)
				(justify left bottom)
				(hide yes)
			)
		)
		(property "Manufacturer" "Bourns"
			(at 105.41 232.41 0)
			(effects
				(font
					(size 1.27 1.27)
					(thickness 0.15)
				)
				(justify left bottom)
				(hide yes)
			)
		)
		(property "License" "Apache-2.0"
			(at 102.87 232.41 0)
			(effects
				(font
					(size 1.27 1.27)
					(thickness 0.15)
				)
				(justify left bottom)
				(hide yes)
			)
		)
		(property "Val" "100k"
			(at 125.73 215.9 90)
			(effects
				(font
					(size 1.27 1.27)
					(thickness 0.15)
				)
				(justify right)
			)
		)
		(property "Tolerance" "1%"
			(at 118.11 232.41 0)
			(effects
				(font
					(size 1.27 1.27)
				)
				(justify left bottom)
				(hide yes)
			)
		)
		(property "Author" "Antmicro"
			(at 100.33 232.41 0)
			(effects
				(font
					(size 1.27 1.27)
					(thickness 0.15)
				)
				(justify left bottom)
				(hide yes)
			)
		)
		(pin "1"
		)
		(pin "2"
		)
		(instances
			(project "thunderbolt-gpu-adapter"
				(path ""
					(reference "R22")
					(unit 1)
				)
			)
		)
	)
	(symbol
		(lib_id "antmicropower:GND")
		(at 172.72 88.9 0)
		(unit 1)
		(exclude_from_sim no)
		(in_bom yes)
		(on_board yes)
		(dnp no)
		(property "Reference" "#PWR070"
			(at 172.72 95.25 0)
			(effects
				(font
					(size 1.27 1.27)
				)
				(hide yes)
			)
		)
		(property "Value" "GND"
			(at 172.72 92.71 0)
			(effects
				(font
					(size 1.27 1.27)
				)
			)
		)
		(property "Footprint" ""
			(at 172.72 88.9 0)
			(effects
				(font
					(size 1.27 1.27)
				)
				(hide yes)
			)
		)
		(property "Datasheet" ""
			(at 172.72 88.9 0)
			(effects
				(font
					(size 1.27 1.27)
				)
				(hide yes)
			)
		)
		(property "Description" ""
			(at 172.72 88.9 0)
			(effects
				(font
					(size 1.27 1.27)
				)
				(hide yes)
			)
		)
		(property "Author" "Antmicro"
			(at 181.61 96.52 0)
			(effects
				(font
					(size 1.27 1.27)
					(thickness 0.15)
				)
				(justify left bottom)
				(hide yes)
			)
		)
		(property "License" "Apache-2.0"
			(at 181.61 99.06 0)
			(effects
				(font
					(size 1.27 1.27)
					(thickness 0.15)
				)
				(justify left bottom)
				(hide yes)
			)
		)
		(pin "1"
		)
		(instances
			(project "thunderbolt-gpu-adapter"
				(path ""
					(reference "#PWR070")
					(unit 1)
				)
			)
		)
	)
	(symbol
		(lib_id "antmicroCapacitors0603:C_10u_0603")
		(at 264.16 127 90)
		(unit 1)
		(exclude_from_sim no)
		(in_bom yes)
		(on_board yes)
		(dnp no)
		(property "Reference" "C134"
			(at 265.43 123.19 90)
			(effects
				(font
					(size 1.27 1.27)
					(thickness 0.15)
				)
				(justify right)
			)
		)
		(property "Value" "C_10u_0603"
			(at 274.32 106.68 0)
			(effects
				(font
					(size 1.27 1.27)
					(thickness 0.15)
				)
				(justify left bottom)
				(hide yes)
			)
		)
		(property "Footprint" "antmicro-footprints:C_0603_1608Metric"
			(at 276.86 106.68 0)
			(effects
				(font
					(size 1.27 1.27)
					(thickness 0.15)
				)
				(justify left bottom)
				(hide yes)
			)
		)
		(property "Datasheet" "https://www.murata.com/products/productdetail?partno=GRM188R61A106KE69%23"
			(at 279.4 106.68 0)
			(effects
				(font
					(size 1.27 1.27)
					(thickness 0.15)
				)
				(justify left bottom)
				(hide yes)
			)
		)
		(property "Description" ""
			(at 264.16 127 0)
			(effects
				(font
					(size 1.27 1.27)
				)
				(hide yes)
			)
		)
		(property "MPN" "GRM188R61A106KE69D"
			(at 281.94 106.68 0)
			(effects
				(font
					(size 1.27 1.27)
					(thickness 0.15)
				)
				(justify left bottom)
				(hide yes)
			)
		)
		(property "Manufacturer" "Murata"
			(at 284.48 106.68 0)
			(effects
				(font
					(size 1.27 1.27)
					(thickness 0.15)
				)
				(justify left bottom)
				(hide yes)
			)
		)
		(property "License" "Apache-2.0"
			(at 287.02 106.68 0)
			(effects
				(font
					(size 1.27 1.27)
					(thickness 0.15)
				)
				(justify left bottom)
				(hide yes)
			)
		)
		(property "Author" "Antmicro"
			(at 289.56 106.68 0)
			(effects
				(font
					(size 1.27 1.27)
					(thickness 0.15)
				)
				(justify left bottom)
				(hide yes)
			)
		)
		(property "Val" "10u"
			(at 265.43 125.73 90)
			(effects
				(font
					(size 1.27 1.27)
					(thickness 0.15)
				)
				(justify right)
			)
		)
		(property "Voltage" ""
			(at 292.1 106.68 0)
			(effects
				(font
					(size 1.27 1.27)
				)
				(justify left bottom)
				(hide yes)
			)
		)
		(property "Dielectric" "template_dielectric"
			(at 294.64 106.68 0)
			(effects
				(font
					(size 1.27 1.27)
				)
				(justify left bottom)
				(hide yes)
			)
		)
		(pin "1"
		)
		(pin "2"
		)
		(instances
			(project "thunderbolt-gpu-adapter"
				(path ""
					(reference "C134")
					(unit 1)
				)
			)
		)
	)
	(symbol
		(lib_id "antmicroResistors0402:R_2k2_0402")
		(at 34.29 68.58 90)
		(unit 1)
		(exclude_from_sim no)
		(in_bom yes)
		(on_board yes)
		(dnp no)
		(property "Reference" "R3"
			(at 35.56 64.77 90)
			(effects
				(font
					(size 1.27 1.27)
					(thickness 0.15)
				)
				(justify right)
			)
		)
		(property "Value" "R_2k2_0402"
			(at 46.99 48.26 0)
			(effects
				(font
					(size 1.27 1.27)
					(thickness 0.15)
				)
				(justify left bottom)
				(hide yes)
			)
		)
		(property "Footprint" "antmicro-footprints:R_0402_1005Metric"
			(at 49.53 48.26 0)
			(effects
				(font
					(size 1.27 1.27)
					(thickness 0.15)
				)
				(justify left bottom)
				(hide yes)
			)
		)
		(property "Datasheet" "https://www.bourns.com/docs/product-datasheets/cr.pdf"
			(at 52.07 48.26 0)
			(effects
				(font
					(size 1.27 1.27)
					(thickness 0.15)
				)
				(justify left bottom)
				(hide yes)
			)
		)
		(property "Description" ""
			(at 34.29 68.58 0)
			(effects
				(font
					(size 1.27 1.27)
				)
				(hide yes)
			)
		)
		(property "MPN" "CR0402-FX-2201GLF"
			(at 54.61 48.26 0)
			(effects
				(font
					(size 1.27 1.27)
					(thickness 0.15)
				)
				(justify left bottom)
				(hide yes)
			)
		)
		(property "Manufacturer" "Bourns"
			(at 57.15 48.26 0)
			(effects
				(font
					(size 1.27 1.27)
					(thickness 0.15)
				)
				(justify left bottom)
				(hide yes)
			)
		)
		(property "License" "Apache-2.0"
			(at 59.69 48.26 0)
			(effects
				(font
					(size 1.27 1.27)
					(thickness 0.15)
				)
				(justify left bottom)
				(hide yes)
			)
		)
		(property "Val" "2k2"
			(at 35.56 67.31 90)
			(effects
				(font
					(size 1.27 1.27)
					(thickness 0.15)
				)
				(justify right)
			)
		)
		(property "Tolerance" "1%"
			(at 44.45 48.26 0)
			(effects
				(font
					(size 1.27 1.27)
				)
				(justify left bottom)
				(hide yes)
			)
		)
		(property "Author" "Antmicro"
			(at 62.23 48.26 0)
			(effects
				(font
					(size 1.27 1.27)
					(thickness 0.15)
				)
				(justify left bottom)
				(hide yes)
			)
		)
		(pin "1"
		)
		(pin "2"
		)
		(instances
			(project "thunderbolt-gpu-adapter"
				(path ""
					(reference "R3")
					(unit 1)
				)
			)
		)
	)
	(symbol
		(lib_id "antmicropower:GND")
		(at 148.59 69.85 0)
		(unit 1)
		(exclude_from_sim no)
		(in_bom yes)
		(on_board yes)
		(dnp no)
		(property "Reference" "#PWR053"
			(at 148.59 76.2 0)
			(effects
				(font
					(size 1.27 1.27)
				)
				(hide yes)
			)
		)
		(property "Value" "GND"
			(at 148.59 73.66 0)
			(effects
				(font
					(size 1.27 1.27)
				)
			)
		)
		(property "Footprint" ""
			(at 148.59 69.85 0)
			(effects
				(font
					(size 1.27 1.27)
				)
				(hide yes)
			)
		)
		(property "Datasheet" ""
			(at 148.59 69.85 0)
			(effects
				(font
					(size 1.27 1.27)
				)
				(hide yes)
			)
		)
		(property "Description" ""
			(at 148.59 69.85 0)
			(effects
				(font
					(size 1.27 1.27)
				)
				(hide yes)
			)
		)
		(property "Author" "Antmicro"
			(at 157.48 77.47 0)
			(effects
				(font
					(size 1.27 1.27)
					(thickness 0.15)
				)
				(justify left bottom)
				(hide yes)
			)
		)
		(property "License" "Apache-2.0"
			(at 157.48 80.01 0)
			(effects
				(font
					(size 1.27 1.27)
					(thickness 0.15)
				)
				(justify left bottom)
				(hide yes)
			)
		)
		(pin "1"
		)
		(instances
			(project "thunderbolt-gpu-adapter"
				(path ""
					(reference "#PWR053")
					(unit 1)
				)
			)
		)
	)
	(symbol
		(lib_id "antmicroCapacitorsmisc:C_22u_25V_0805")
		(at 173.99 55.88 90)
		(unit 1)
		(exclude_from_sim no)
		(in_bom yes)
		(on_board yes)
		(dnp yes)
		(fields_autoplaced yes)
		(property "Reference" "C42"
			(at 176.53 50.7936 90)
			(effects
				(font
					(size 1.27 1.27)
					(thickness 0.15)
				)
				(justify right)
			)
		)
		(property "Value" "C_22u_25V_0805"
			(at 184.15 35.56 0)
			(effects
				(font
					(size 1.27 1.27)
					(thickness 0.15)
				)
				(justify left bottom)
				(hide yes)
			)
		)
		(property "Footprint" "antmicro-footprints:C_0805_2012Metric"
			(at 186.69 35.56 0)
			(effects
				(font
					(size 1.27 1.27)
					(thickness 0.15)
				)
				(justify left bottom)
				(hide yes)
			)
		)
		(property "Datasheet" "https://product.samsungsem.com/mlcc/CL21A226MAYNNN.do"
			(at 189.23 35.56 0)
			(effects
				(font
					(size 1.27 1.27)
					(thickness 0.15)
				)
				(justify left bottom)
				(hide yes)
			)
		)
		(property "Description" ""
			(at 173.99 55.88 0)
			(effects
				(font
					(size 1.27 1.27)
				)
				(hide yes)
			)
		)
		(property "MPN" "CL21A226MAYNNNE"
			(at 191.77 35.56 0)
			(effects
				(font
					(size 1.27 1.27)
					(thickness 0.15)
				)
				(justify left bottom)
				(hide yes)
			)
		)
		(property "Manufacturer" "Samsung Electro-Mechanics"
			(at 194.31 35.56 0)
			(effects
				(font
					(size 1.27 1.27)
					(thickness 0.15)
				)
				(justify left bottom)
				(hide yes)
			)
		)
		(property "License" "Apache-2.0"
			(at 196.85 35.56 0)
			(effects
				(font
					(size 1.27 1.27)
					(thickness 0.15)
				)
				(justify left bottom)
				(hide yes)
			)
		)
		(property "Val" "22u"
			(at 176.53 53.3336 90)
			(effects
				(font
					(size 1.27 1.27)
					(thickness 0.15)
				)
				(justify right)
			)
		)
		(property "Voltage" "25V"
			(at 176.53 55.8736 90)
			(effects
				(font
					(size 1.27 1.27)
				)
				(justify right)
			)
		)
		(property "Dielectric" "X5R"
			(at 204.47 35.56 0)
			(effects
				(font
					(size 1.27 1.27)
				)
				(justify left bottom)
				(hide yes)
			)
		)
		(property "Author" "Antmicro"
			(at 199.39 35.56 0)
			(effects
				(font
					(size 1.27 1.27)
					(thickness 0.15)
				)
				(justify left bottom)
				(hide yes)
			)
		)
		(pin "1"
		)
		(pin "2"
		)
		(instances
			(project "thunderbolt-gpu-adapter"
				(path ""
					(reference "C42")
					(unit 1)
				)
			)
		)
	)
	(symbol
		(lib_id "antmicroCapacitors0402:C_10u_0402")
		(at 139.7 54.61 0)
		(unit 1)
		(exclude_from_sim no)
		(in_bom yes)
		(on_board yes)
		(dnp no)
		(property "Reference" "C39"
			(at 139.7 55.88 0)
			(effects
				(font
					(size 1.27 1.27)
					(thickness 0.15)
				)
			)
		)
		(property "Value" "C_10u_0402"
			(at 160.02 64.77 0)
			(effects
				(font
					(size 1.27 1.27)
					(thickness 0.15)
				)
				(justify left bottom)
				(hide yes)
			)
		)
		(property "Footprint" "antmicro-footprints:C_0402_1005Metric"
			(at 160.02 67.31 0)
			(effects
				(font
					(size 1.27 1.27)
					(thickness 0.15)
				)
				(justify left bottom)
				(hide yes)
			)
		)
		(property "Datasheet" "https://www.yageo.com/en/Chart/Download/pdf/CC0402MRX5R5BB106"
			(at 160.02 69.85 0)
			(effects
				(font
					(size 1.27 1.27)
					(thickness 0.15)
				)
				(justify left bottom)
				(hide yes)
			)
		)
		(property "Description" ""
			(at 139.7 54.61 0)
			(effects
				(font
					(size 1.27 1.27)
				)
				(hide yes)
			)
		)
		(property "MPN" "CC0402MRX5R5BB106"
			(at 160.02 72.39 0)
			(effects
				(font
					(size 1.27 1.27)
					(thickness 0.15)
				)
				(justify left bottom)
				(hide yes)
			)
		)
		(property "Manufacturer" "YAGEO"
			(at 160.02 74.93 0)
			(effects
				(font
					(size 1.27 1.27)
					(thickness 0.15)
				)
				(justify left bottom)
				(hide yes)
			)
		)
		(property "License" "Apache-2.0"
			(at 160.02 77.47 0)
			(effects
				(font
					(size 1.27 1.27)
					(thickness 0.15)
				)
				(justify left bottom)
				(hide yes)
			)
		)
		(property "Val" "10u"
			(at 144.78 55.88 0)
			(effects
				(font
					(size 1.27 1.27)
					(thickness 0.15)
				)
			)
		)
		(property "Voltage" ""
			(at 160.02 82.55 0)
			(effects
				(font
					(size 1.27 1.27)
				)
				(justify left bottom)
				(hide yes)
			)
		)
		(property "Dielectric" ""
			(at 160.02 85.09 0)
			(effects
				(font
					(size 1.27 1.27)
				)
				(justify left bottom)
				(hide yes)
			)
		)
		(property "Author" "Antmicro"
			(at 160.02 80.01 0)
			(effects
				(font
					(size 1.27 1.27)
					(thickness 0.15)
				)
				(justify left bottom)
				(hide yes)
			)
		)
		(pin "1"
		)
		(pin "2"
		)
		(instances
			(project "thunderbolt-gpu-adapter"
				(path ""
					(reference "C39")
					(unit 1)
				)
			)
		)
	)
	(symbol
		(lib_id "antmicroTransistorsFETsMOSFETsSingle:SI7613DN-T1-GE3")
		(at 247.65 69.85 270)
		(mirror x)
		(unit 1)
		(exclude_from_sim no)
		(in_bom yes)
		(on_board yes)
		(dnp no)
		(fields_autoplaced yes)
		(property "Reference" "Q10"
			(at 250.19 55.88 90)
			(effects
				(font
					(size 1.524 1.524)
				)
			)
		)
		(property "Value" "SI7613DN-T1-GE3"
			(at 250.19 54.61 0)
			(effects
				(font
					(size 1.27 1.27)
					(thickness 0.15)
				)
				(justify left bottom)
				(hide yes)
			)
		)
		(property "Footprint" "antmicro-footprints:Vishay_PowerPAK_1212-8_Single"
			(at 248.92 54.61 0)
			(effects
				(font
					(size 1.27 1.27)
					(thickness 0.15)
				)
				(justify left bottom)
				(hide yes)
			)
		)
		(property "Datasheet" "https://www.vishay.com/docs/64809/si7613dn.pdf"
			(at 246.38 54.61 0)
			(effects
				(font
					(size 1.27 1.27)
					(thickness 0.15)
				)
				(justify left bottom)
				(hide yes)
			)
		)
		(property "Description" ""
			(at 247.65 69.85 0)
			(effects
				(font
					(size 1.27 1.27)
				)
				(hide yes)
			)
		)
		(property "MPN" "SI7613DN-T1-GE3"
			(at 250.19 58.42 90)
			(effects
				(font
					(size 1.27 1.27)
					(thickness 0.15)
				)
			)
		)
		(property "Manufacturer" "Vishay"
			(at 240.03 54.61 0)
			(effects
				(font
					(size 1.27 1.27)
					(thickness 0.15)
				)
				(justify left bottom)
				(hide yes)
			)
		)
		(property "Author" "Antmicro"
			(at 237.49 54.61 0)
			(effects
				(font
					(size 1.27 1.27)
					(thickness 0.15)
				)
				(justify left bottom)
				(hide yes)
			)
		)
		(property "License" "Apache-2.0"
			(at 234.95 54.61 0)
			(effects
				(font
					(size 1.27 1.27)
					(thickness 0.15)
				)
				(justify left bottom)
				(hide yes)
			)
		)
		(pin "1"
		)
		(pin "2"
		)
		(pin "3"
		)
		(pin "4"
		)
		(pin "5"
		)
		(instances
			(project "thunderbolt-gpu-adapter"
				(path ""
					(reference "Q10")
					(unit 1)
				)
			)
		)
	)
	(symbol
		(lib_id "antmicropower:GND")
		(at 240.03 128.27 0)
		(unit 1)
		(exclude_from_sim no)
		(in_bom yes)
		(on_board yes)
		(dnp no)
		(property "Reference" "#PWR0195"
			(at 240.03 134.62 0)
			(effects
				(font
					(size 1.27 1.27)
				)
				(hide yes)
			)
		)
		(property "Value" "GND"
			(at 240.03 132.08 0)
			(effects
				(font
					(size 1.27 1.27)
				)
			)
		)
		(property "Footprint" ""
			(at 240.03 128.27 0)
			(effects
				(font
					(size 1.27 1.27)
				)
				(hide yes)
			)
		)
		(property "Datasheet" ""
			(at 240.03 128.27 0)
			(effects
				(font
					(size 1.27 1.27)
				)
				(hide yes)
			)
		)
		(property "Description" ""
			(at 240.03 128.27 0)
			(effects
				(font
					(size 1.27 1.27)
				)
				(hide yes)
			)
		)
		(property "Author" "Antmicro"
			(at 248.92 135.89 0)
			(effects
				(font
					(size 1.27 1.27)
					(thickness 0.15)
				)
				(justify left bottom)
				(hide yes)
			)
		)
		(property "License" "Apache-2.0"
			(at 248.92 138.43 0)
			(effects
				(font
					(size 1.27 1.27)
					(thickness 0.15)
				)
				(justify left bottom)
				(hide yes)
			)
		)
		(pin "1"
		)
		(instances
			(project "thunderbolt-gpu-adapter"
				(path ""
					(reference "#PWR0195")
					(unit 1)
				)
			)
		)
	)
	(symbol
		(lib_id "antmicropower:GND")
		(at 62.23 138.43 0)
		(unit 1)
		(exclude_from_sim no)
		(in_bom yes)
		(on_board yes)
		(dnp no)
		(property "Reference" "#PWR034"
			(at 62.23 144.78 0)
			(effects
				(font
					(size 1.27 1.27)
				)
				(hide yes)
			)
		)
		(property "Value" "GND"
			(at 62.23 142.24 0)
			(effects
				(font
					(size 1.27 1.27)
				)
			)
		)
		(property "Footprint" ""
			(at 62.23 138.43 0)
			(effects
				(font
					(size 1.27 1.27)
				)
				(hide yes)
			)
		)
		(property "Datasheet" ""
			(at 62.23 138.43 0)
			(effects
				(font
					(size 1.27 1.27)
				)
				(hide yes)
			)
		)
		(property "Description" ""
			(at 62.23 138.43 0)
			(effects
				(font
					(size 1.27 1.27)
				)
				(hide yes)
			)
		)
		(property "Author" "Antmicro"
			(at 71.12 146.05 0)
			(effects
				(font
					(size 1.27 1.27)
					(thickness 0.15)
				)
				(justify left bottom)
				(hide yes)
			)
		)
		(property "License" "Apache-2.0"
			(at 71.12 148.59 0)
			(effects
				(font
					(size 1.27 1.27)
					(thickness 0.15)
				)
				(justify left bottom)
				(hide yes)
			)
		)
		(pin "1"
		)
		(instances
			(project "thunderbolt-gpu-adapter"
				(path ""
					(reference "#PWR034")
					(unit 1)
				)
			)
		)
	)
	(symbol
		(lib_id "antmicropower:GND")
		(at 237.49 95.25 0)
		(unit 1)
		(exclude_from_sim no)
		(in_bom yes)
		(on_board yes)
		(dnp no)
		(property "Reference" "#PWR0169"
			(at 237.49 101.6 0)
			(effects
				(font
					(size 1.27 1.27)
				)
				(hide yes)
			)
		)
		(property "Value" "GND"
			(at 237.49 99.06 0)
			(effects
				(font
					(size 1.27 1.27)
				)
			)
		)
		(property "Footprint" ""
			(at 237.49 95.25 0)
			(effects
				(font
					(size 1.27 1.27)
				)
				(hide yes)
			)
		)
		(property "Datasheet" ""
			(at 237.49 95.25 0)
			(effects
				(font
					(size 1.27 1.27)
				)
				(hide yes)
			)
		)
		(property "Description" ""
			(at 237.49 95.25 0)
			(effects
				(font
					(size 1.27 1.27)
				)
				(hide yes)
			)
		)
		(property "Author" "Antmicro"
			(at 246.38 102.87 0)
			(effects
				(font
					(size 1.27 1.27)
					(thickness 0.15)
				)
				(justify left bottom)
				(hide yes)
			)
		)
		(property "License" "Apache-2.0"
			(at 246.38 105.41 0)
			(effects
				(font
					(size 1.27 1.27)
					(thickness 0.15)
				)
				(justify left bottom)
				(hide yes)
			)
		)
		(pin "1"
		)
		(instances
			(project "thunderbolt-gpu-adapter"
				(path ""
					(reference "#PWR0169")
					(unit 1)
				)
			)
		)
	)
	(symbol
		(lib_id "antmicroCapacitors0402:C_100n_0402")
		(at 54.61 66.04 90)
		(unit 1)
		(exclude_from_sim no)
		(in_bom yes)
		(on_board yes)
		(dnp no)
		(property "Reference" "C148"
			(at 54.61 61.595 90)
			(effects
				(font
					(size 1.27 1.27)
					(thickness 0.15)
				)
				(justify right)
			)
		)
		(property "Value" "C_100n_0402"
			(at 64.77 45.72 0)
			(effects
				(font
					(size 1.27 1.27)
					(thickness 0.15)
				)
				(justify left bottom)
				(hide yes)
			)
		)
		(property "Footprint" "antmicro-footprints:C_0402_1005Metric"
			(at 67.31 45.72 0)
			(effects
				(font
					(size 1.27 1.27)
					(thickness 0.15)
				)
				(justify left bottom)
				(hide yes)
			)
		)
		(property "Datasheet" "https://www.murata.com/products/productdetail?partno=GRM155R61H104KE14%23"
			(at 69.85 45.72 0)
			(effects
				(font
					(size 1.27 1.27)
					(thickness 0.15)
				)
				(justify left bottom)
				(hide yes)
			)
		)
		(property "Description" ""
			(at 54.61 66.04 0)
			(effects
				(font
					(size 1.27 1.27)
				)
				(hide yes)
			)
		)
		(property "MPN" "GRM155R61H104KE14D"
			(at 72.39 45.72 0)
			(effects
				(font
					(size 1.27 1.27)
					(thickness 0.15)
				)
				(justify left bottom)
				(hide yes)
			)
		)
		(property "Manufacturer" "Murata"
			(at 74.93 45.72 0)
			(effects
				(font
					(size 1.27 1.27)
					(thickness 0.15)
				)
				(justify left bottom)
				(hide yes)
			)
		)
		(property "License" "Apache-2.0"
			(at 77.47 45.72 0)
			(effects
				(font
					(size 1.27 1.27)
					(thickness 0.15)
				)
				(justify left bottom)
				(hide yes)
			)
		)
		(property "Author" "Antmicro"
			(at 80.01 45.72 0)
			(effects
				(font
					(size 1.27 1.27)
					(thickness 0.15)
				)
				(justify left bottom)
				(hide yes)
			)
		)
		(property "Val" "100n"
			(at 54.61 65.405 90)
			(effects
				(font
					(size 1.27 1.27)
					(thickness 0.15)
				)
				(justify right)
			)
		)
		(property "Voltage" "50V"
			(at 82.55 45.72 0)
			(effects
				(font
					(size 1.27 1.27)
				)
				(justify left bottom)
				(hide yes)
			)
		)
		(property "Dielectric" "X5R"
			(at 85.09 45.72 0)
			(effects
				(font
					(size 1.27 1.27)
				)
				(justify left bottom)
				(hide yes)
			)
		)
		(pin "1"
		)
		(pin "2"
		)
		(instances
			(project "thunderbolt-gpu-adapter"
				(path ""
					(reference "C148")
					(unit 1)
				)
			)
		)
	)
	(symbol
		(lib_id "antmicroResistors0603:R_0R_22.4A_0603")
		(at 262.89 262.89 180)
		(unit 1)
		(exclude_from_sim no)
		(in_bom yes)
		(on_board yes)
		(dnp no)
		(fields_autoplaced yes)
		(property "Reference" "R98"
			(at 260.35 260.985 0)
			(effects
				(font
					(size 1.27 1.27)
					(thickness 0.15)
				)
			)
		)
		(property "Value" "R_0R_22.4A_0603"
			(at 260.35 257.175 0)
			(effects
				(font
					(size 1.27 1.27)
					(thickness 0.15)
				)
			)
		)
		(property "Footprint" "antmicro-footprints:R_0603_1608Metric"
			(at 240.03 250.19 0)
			(effects
				(font
					(size 1.27 1.27)
					(thickness 0.15)
				)
				(justify left bottom)
				(hide yes)
			)
		)
		(property "Datasheet" "https://fscdn.rohm.com/en/products/databook/datasheet/passive/resistor/chip_resistor/pmr-jpw-e.pdf"
			(at 240.03 247.65 0)
			(effects
				(font
					(size 1.27 1.27)
					(thickness 0.15)
				)
				(justify left bottom)
				(hide yes)
			)
		)
		(property "Description" ""
			(at 262.89 262.89 0)
			(effects
				(font
					(size 1.27 1.27)
				)
				(hide yes)
			)
		)
		(property "Manufacturer" "ROHM Semiconductor"
			(at 240.03 245.11 0)
			(effects
				(font
					(size 1.27 1.27)
					(thickness 0.15)
				)
				(justify left bottom)
				(hide yes)
			)
		)
		(property "MPN" "PMR03EZPJ000"
			(at 240.03 242.57 0)
			(effects
				(font
					(size 1.27 1.27)
					(thickness 0.15)
				)
				(justify left bottom)
				(hide yes)
			)
		)
		(property "Val" "0R"
			(at 260.35 262.89 0)
			(effects
				(font
					(size 1.27 1.27)
					(thickness 0.15)
				)
			)
		)
		(property "Author" "Antmicro"
			(at 240.03 240.03 0)
			(effects
				(font
					(size 1.27 1.27)
					(thickness 0.15)
				)
				(justify left bottom)
				(hide yes)
			)
		)
		(property "License" "Apache-2.0"
			(at 240.03 237.49 0)
			(effects
				(font
					(size 1.27 1.27)
					(thickness 0.15)
				)
				(justify left bottom)
				(hide yes)
			)
		)
		(property "Max. Curr." "22.4A"
			(at 247.65 242.57 0)
			(effects
				(font
					(size 1.27 1.27)
					(thickness 0.15)
				)
				(justify left bottom)
			)
		)
		(property "Tolerance" "template_tolerance"
			(at 242.57 252.73 0)
			(effects
				(font
					(size 1.27 1.27)
				)
				(justify left bottom)
				(hide yes)
			)
		)
		(pin "1"
		)
		(pin "2"
		)
		(instances
			(project "thunderbolt-gpu-adapter"
				(path ""
					(reference "R98")
					(unit 1)
				)
			)
		)
	)
	(symbol
		(lib_id "antmicroResistors0402:R_12k_0402")
		(at 172.72 250.19 90)
		(unit 1)
		(exclude_from_sim no)
		(in_bom yes)
		(on_board yes)
		(dnp no)
		(fields_autoplaced yes)
		(property "Reference" "R25"
			(at 175.26 246.38 90)
			(effects
				(font
					(size 1.27 1.27)
					(thickness 0.15)
				)
				(justify right)
			)
		)
		(property "Value" "R_12k_0402"
			(at 185.42 229.87 0)
			(effects
				(font
					(size 1.27 1.27)
					(thickness 0.15)
				)
				(justify left bottom)
				(hide yes)
			)
		)
		(property "Footprint" "antmicro-footprints:R_0402_1005Metric"
			(at 187.96 229.87 0)
			(effects
				(font
					(size 1.27 1.27)
					(thickness 0.15)
				)
				(justify left bottom)
				(hide yes)
			)
		)
		(property "Datasheet" "https://www.bourns.com/docs/product-datasheets/cr.pdf"
			(at 190.5 229.87 0)
			(effects
				(font
					(size 1.27 1.27)
					(thickness 0.15)
				)
				(justify left bottom)
				(hide yes)
			)
		)
		(property "Description" ""
			(at 172.72 250.19 0)
			(effects
				(font
					(size 1.27 1.27)
				)
				(hide yes)
			)
		)
		(property "MPN" "CR0402-FX-1202GLF"
			(at 193.04 229.87 0)
			(effects
				(font
					(size 1.27 1.27)
					(thickness 0.15)
				)
				(justify left bottom)
				(hide yes)
			)
		)
		(property "Manufacturer" "Bourns"
			(at 195.58 229.87 0)
			(effects
				(font
					(size 1.27 1.27)
					(thickness 0.15)
				)
				(justify left bottom)
				(hide yes)
			)
		)
		(property "License" "Apache-2.0"
			(at 198.12 229.87 0)
			(effects
				(font
					(size 1.27 1.27)
					(thickness 0.15)
				)
				(justify left bottom)
				(hide yes)
			)
		)
		(property "Val" "12k"
			(at 175.26 248.92 90)
			(effects
				(font
					(size 1.27 1.27)
					(thickness 0.15)
				)
				(justify right)
			)
		)
		(property "Tolerance" "1%"
			(at 182.88 229.87 0)
			(effects
				(font
					(size 1.27 1.27)
				)
				(justify left bottom)
				(hide yes)
			)
		)
		(property "Author" "Antmicro"
			(at 200.66 229.87 0)
			(effects
				(font
					(size 1.27 1.27)
					(thickness 0.15)
				)
				(justify left bottom)
				(hide yes)
			)
		)
		(pin "1"
		)
		(pin "2"
		)
		(instances
			(project "thunderbolt-gpu-adapter"
				(path ""
					(reference "R25")
					(unit 1)
				)
			)
		)
	)
	(symbol
		(lib_id "antmicroLEDIndicationDiscrete:LED_G_0603_KP-1608CGCK")
		(at 199.39 355.6 90)
		(unit 1)
		(exclude_from_sim no)
		(in_bom yes)
		(on_board yes)
		(dnp no)
		(fields_autoplaced yes)
		(property "Reference" "D2"
			(at 201.93 351.79 90)
			(effects
				(font
					(size 1.27 1.27)
					(thickness 0.15)
				)
				(justify right)
			)
		)
		(property "Value" "LED_G_0603_KP-1608CGCK"
			(at 195.58 350.5201 90)
			(effects
				(font
					(size 1.27 1.27)
					(thickness 0.15)
				)
				(justify left)
				(hide yes)
			)
		)
		(property "Footprint" "antmicro-footprints:LED_0603_1608Metric_G"
			(at 209.55 332.74 0)
			(effects
				(font
					(size 1.27 1.27)
					(thickness 0.15)
				)
				(justify left bottom)
				(hide yes)
			)
		)
		(property "Datasheet" "http://www.kingbright.com/attachments/file/psearch//000/00/00/KP-1608CGCK(Ver.23B).pdf"
			(at 212.09 332.74 0)
			(effects
				(font
					(size 1.27 1.27)
					(thickness 0.15)
				)
				(justify left bottom)
				(hide yes)
			)
		)
		(property "Description" ""
			(at 199.39 355.6 0)
			(effects
				(font
					(size 1.27 1.27)
				)
				(hide yes)
			)
		)
		(property "MPN" "KP-1608CGCK"
			(at 214.63 332.74 0)
			(effects
				(font
					(size 1.27 1.27)
					(thickness 0.15)
				)
				(justify left bottom)
				(hide yes)
			)
		)
		(property "Manufacturer" "Kingbright"
			(at 217.17 332.74 0)
			(effects
				(font
					(size 1.27 1.27)
					(thickness 0.15)
				)
				(justify left bottom)
				(hide yes)
			)
		)
		(property "License" "Apache-2.0"
			(at 222.25 332.74 0)
			(effects
				(font
					(size 1.27 1.27)
					(thickness 0.15)
				)
				(justify left bottom)
				(hide yes)
			)
		)
		(property "Author" "Antmicro"
			(at 219.71 332.74 0)
			(effects
				(font
					(size 1.27 1.27)
					(thickness 0.15)
				)
				(justify left bottom)
				(hide yes)
			)
		)
		(property "Color" "Green"
			(at 201.93 354.33 90)
			(effects
				(font
					(size 1.27 1.27)
				)
				(justify right)
			)
		)
		(pin "1"
		)
		(pin "2"
		)
		(instances
			(project "thunderbolt-gpu-adapter"
				(path ""
					(reference "D2")
					(unit 1)
				)
			)
		)
	)
	(symbol
		(lib_id "antmicropower:GND")
		(at 181.61 88.9 0)
		(unit 1)
		(exclude_from_sim no)
		(in_bom yes)
		(on_board yes)
		(dnp no)
		(property "Reference" "#PWR072"
			(at 181.61 95.25 0)
			(effects
				(font
					(size 1.27 1.27)
				)
				(hide yes)
			)
		)
		(property "Value" "GND"
			(at 181.61 92.71 0)
			(effects
				(font
					(size 1.27 1.27)
				)
			)
		)
		(property "Footprint" ""
			(at 181.61 88.9 0)
			(effects
				(font
					(size 1.27 1.27)
				)
				(hide yes)
			)
		)
		(property "Datasheet" ""
			(at 181.61 88.9 0)
			(effects
				(font
					(size 1.27 1.27)
				)
				(hide yes)
			)
		)
		(property "Description" ""
			(at 181.61 88.9 0)
			(effects
				(font
					(size 1.27 1.27)
				)
				(hide yes)
			)
		)
		(property "Author" "Antmicro"
			(at 190.5 96.52 0)
			(effects
				(font
					(size 1.27 1.27)
					(thickness 0.15)
				)
				(justify left bottom)
				(hide yes)
			)
		)
		(property "License" "Apache-2.0"
			(at 190.5 99.06 0)
			(effects
				(font
					(size 1.27 1.27)
					(thickness 0.15)
				)
				(justify left bottom)
				(hide yes)
			)
		)
		(pin "1"
		)
		(instances
			(project "thunderbolt-gpu-adapter"
				(path ""
					(reference "#PWR072")
					(unit 1)
				)
			)
		)
	)
	(symbol
		(lib_id "antmicropower:GND")
		(at 60.96 67.31 0)
		(unit 1)
		(exclude_from_sim no)
		(in_bom yes)
		(on_board yes)
		(dnp no)
		(property "Reference" "#PWR033"
			(at 60.96 73.66 0)
			(effects
				(font
					(size 1.27 1.27)
				)
				(hide yes)
			)
		)
		(property "Value" "GND"
			(at 60.96 71.12 0)
			(effects
				(font
					(size 1.27 1.27)
				)
			)
		)
		(property "Footprint" ""
			(at 60.96 67.31 0)
			(effects
				(font
					(size 1.27 1.27)
				)
				(hide yes)
			)
		)
		(property "Datasheet" ""
			(at 60.96 67.31 0)
			(effects
				(font
					(size 1.27 1.27)
				)
				(hide yes)
			)
		)
		(property "Description" ""
			(at 60.96 67.31 0)
			(effects
				(font
					(size 1.27 1.27)
				)
				(hide yes)
			)
		)
		(property "Author" "Antmicro"
			(at 69.85 74.93 0)
			(effects
				(font
					(size 1.27 1.27)
					(thickness 0.15)
				)
				(justify left bottom)
				(hide yes)
			)
		)
		(property "License" "Apache-2.0"
			(at 69.85 77.47 0)
			(effects
				(font
					(size 1.27 1.27)
					(thickness 0.15)
				)
				(justify left bottom)
				(hide yes)
			)
		)
		(pin "1"
		)
		(instances
			(project "thunderbolt-gpu-adapter"
				(path ""
					(reference "#PWR033")
					(unit 1)
				)
			)
		)
	)
	(symbol
		(lib_id "antmicropower:GND")
		(at 54.61 67.31 0)
		(unit 1)
		(exclude_from_sim no)
		(in_bom yes)
		(on_board yes)
		(dnp no)
		(property "Reference" "#PWR0220"
			(at 54.61 73.66 0)
			(effects
				(font
					(size 1.27 1.27)
				)
				(hide yes)
			)
		)
		(property "Value" "GND"
			(at 54.61 71.12 0)
			(effects
				(font
					(size 1.27 1.27)
				)
			)
		)
		(property "Footprint" ""
			(at 54.61 67.31 0)
			(effects
				(font
					(size 1.27 1.27)
				)
				(hide yes)
			)
		)
		(property "Datasheet" ""
			(at 54.61 67.31 0)
			(effects
				(font
					(size 1.27 1.27)
				)
				(hide yes)
			)
		)
		(property "Description" ""
			(at 54.61 67.31 0)
			(effects
				(font
					(size 1.27 1.27)
				)
				(hide yes)
			)
		)
		(property "Author" "Antmicro"
			(at 63.5 74.93 0)
			(effects
				(font
					(size 1.27 1.27)
					(thickness 0.15)
				)
				(justify left bottom)
				(hide yes)
			)
		)
		(property "License" "Apache-2.0"
			(at 63.5 77.47 0)
			(effects
				(font
					(size 1.27 1.27)
					(thickness 0.15)
				)
				(justify left bottom)
				(hide yes)
			)
		)
		(pin "1"
		)
		(instances
			(project "thunderbolt-gpu-adapter"
				(path ""
					(reference "#PWR0220")
					(unit 1)
				)
			)
		)
	)
	(symbol
		(lib_id "antmicropower:GND")
		(at 203.2 212.09 0)
		(unit 1)
		(exclude_from_sim no)
		(in_bom yes)
		(on_board yes)
		(dnp no)
		(property "Reference" "#PWR0241"
			(at 203.2 218.44 0)
			(effects
				(font
					(size 1.27 1.27)
				)
				(hide yes)
			)
		)
		(property "Value" "GND"
			(at 201.295 216.535 0)
			(effects
				(font
					(size 1.27 1.27)
					(thickness 0.15)
				)
				(justify left bottom)
			)
		)
		(property "Footprint" ""
			(at 203.2 212.09 0)
			(effects
				(font
					(size 1.27 1.27)
					(thickness 0.15)
				)
				(justify left bottom)
				(hide yes)
			)
		)
		(property "Datasheet" ""
			(at 203.2 212.09 0)
			(effects
				(font
					(size 1.27 1.27)
					(thickness 0.15)
				)
				(justify left bottom)
				(hide yes)
			)
		)
		(property "Description" ""
			(at 203.2 212.09 0)
			(effects
				(font
					(size 1.27 1.27)
				)
				(hide yes)
			)
		)
		(property "Author" "Antmicro"
			(at 212.09 219.71 0)
			(effects
				(font
					(size 1.27 1.27)
					(thickness 0.15)
				)
				(justify left bottom)
				(hide yes)
			)
		)
		(property "License" "Apache-2.0"
			(at 212.09 222.25 0)
			(effects
				(font
					(size 1.27 1.27)
					(thickness 0.15)
				)
				(justify left bottom)
				(hide yes)
			)
		)
		(pin "1"
		)
		(instances
			(project "thunderbolt-gpu-adapter"
				(path ""
					(reference "#PWR0241")
					(unit 1)
				)
			)
		)
	)
	(symbol
		(lib_id "antmicroResistors0402:R_1k_0402")
		(at 222.25 88.9 0)
		(unit 1)
		(exclude_from_sim no)
		(in_bom yes)
		(on_board yes)
		(dnp yes)
		(fields_autoplaced yes)
		(property "Reference" "R148"
			(at 224.79 92.71 0)
			(effects
				(font
					(size 1.27 1.27)
					(thickness 0.15)
				)
			)
		)
		(property "Value" "R_1k_0402"
			(at 242.57 101.6 0)
			(effects
				(font
					(size 1.27 1.27)
					(thickness 0.15)
				)
				(justify left bottom)
				(hide yes)
			)
		)
		(property "Footprint" "antmicro-footprints:R_0402_1005Metric"
			(at 242.57 104.14 0)
			(effects
				(font
					(size 1.27 1.27)
					(thickness 0.15)
				)
				(justify left bottom)
				(hide yes)
			)
		)
		(property "Datasheet" "https://www.bourns.com/docs/product-datasheets/cr.pdf"
			(at 242.57 106.68 0)
			(effects
				(font
					(size 1.27 1.27)
					(thickness 0.15)
				)
				(justify left bottom)
				(hide yes)
			)
		)
		(property "Description" ""
			(at 222.25 88.9 0)
			(effects
				(font
					(size 1.27 1.27)
				)
				(hide yes)
			)
		)
		(property "MPN" "CR0402-FX-1001GLF"
			(at 242.57 109.22 0)
			(effects
				(font
					(size 1.27 1.27)
					(thickness 0.15)
				)
				(justify left bottom)
				(hide yes)
			)
		)
		(property "Manufacturer" "Bourns"
			(at 242.57 111.76 0)
			(effects
				(font
					(size 1.27 1.27)
					(thickness 0.15)
				)
				(justify left bottom)
				(hide yes)
			)
		)
		(property "License" "Apache-2.0"
			(at 242.57 114.3 0)
			(effects
				(font
					(size 1.27 1.27)
					(thickness 0.15)
				)
				(justify left bottom)
				(hide yes)
			)
		)
		(property "Val" "1k"
			(at 224.79 95.25 0)
			(effects
				(font
					(size 1.27 1.27)
					(thickness 0.15)
				)
			)
		)
		(property "Tolerance" "1%"
			(at 242.57 99.06 0)
			(effects
				(font
					(size 1.27 1.27)
				)
				(justify left bottom)
				(hide yes)
			)
		)
		(property "Author" "Antmicro"
			(at 242.57 116.84 0)
			(effects
				(font
					(size 1.27 1.27)
					(thickness 0.15)
				)
				(justify left bottom)
				(hide yes)
			)
		)
		(pin "1"
		)
		(pin "2"
		)
		(instances
			(project "thunderbolt-gpu-adapter"
				(path ""
					(reference "R148")
					(unit 1)
				)
			)
		)
	)
	(symbol
		(lib_id "antmicropower:GND")
		(at 212.09 212.09 0)
		(unit 1)
		(exclude_from_sim no)
		(in_bom yes)
		(on_board yes)
		(dnp no)
		(property "Reference" "#PWR0242"
			(at 212.09 218.44 0)
			(effects
				(font
					(size 1.27 1.27)
				)
				(hide yes)
			)
		)
		(property "Value" "GND"
			(at 210.185 216.535 0)
			(effects
				(font
					(size 1.27 1.27)
					(thickness 0.15)
				)
				(justify left bottom)
			)
		)
		(property "Footprint" ""
			(at 212.09 212.09 0)
			(effects
				(font
					(size 1.27 1.27)
					(thickness 0.15)
				)
				(justify left bottom)
				(hide yes)
			)
		)
		(property "Datasheet" ""
			(at 212.09 212.09 0)
			(effects
				(font
					(size 1.27 1.27)
					(thickness 0.15)
				)
				(justify left bottom)
				(hide yes)
			)
		)
		(property "Description" ""
			(at 212.09 212.09 0)
			(effects
				(font
					(size 1.27 1.27)
				)
				(hide yes)
			)
		)
		(property "Author" "Antmicro"
			(at 220.98 219.71 0)
			(effects
				(font
					(size 1.27 1.27)
					(thickness 0.15)
				)
				(justify left bottom)
				(hide yes)
			)
		)
		(property "License" "Apache-2.0"
			(at 220.98 222.25 0)
			(effects
				(font
					(size 1.27 1.27)
					(thickness 0.15)
				)
				(justify left bottom)
				(hide yes)
			)
		)
		(pin "1"
		)
		(instances
			(project "thunderbolt-gpu-adapter"
				(path ""
					(reference "#PWR0242")
					(unit 1)
				)
			)
		)
	)
	(symbol
		(lib_id "antmicroResistors0402:R_10k_0402")
		(at 231.14 325.12 90)
		(unit 1)
		(exclude_from_sim no)
		(in_bom yes)
		(on_board yes)
		(dnp no)
		(fields_autoplaced yes)
		(property "Reference" "R94"
			(at 233.68 321.31 90)
			(effects
				(font
					(size 1.27 1.27)
					(thickness 0.15)
				)
				(justify right)
			)
		)
		(property "Value" "R_10k_0402"
			(at 243.84 304.8 0)
			(effects
				(font
					(size 1.27 1.27)
					(thickness 0.15)
				)
				(justify left bottom)
				(hide yes)
			)
		)
		(property "Footprint" "antmicro-footprints:R_0402_1005Metric"
			(at 246.38 304.8 0)
			(effects
				(font
					(size 1.27 1.27)
					(thickness 0.15)
				)
				(justify left bottom)
				(hide yes)
			)
		)
		(property "Datasheet" "https://www.bourns.com/docs/product-datasheets/cr.pdf"
			(at 248.92 304.8 0)
			(effects
				(font
					(size 1.27 1.27)
					(thickness 0.15)
				)
				(justify left bottom)
				(hide yes)
			)
		)
		(property "Description" ""
			(at 231.14 325.12 0)
			(effects
				(font
					(size 1.27 1.27)
				)
				(hide yes)
			)
		)
		(property "MPN" "CR0402-FX-1002GLF"
			(at 251.46 304.8 0)
			(effects
				(font
					(size 1.27 1.27)
					(thickness 0.15)
				)
				(justify left bottom)
				(hide yes)
			)
		)
		(property "Manufacturer" "Bourns"
			(at 254 304.8 0)
			(effects
				(font
					(size 1.27 1.27)
					(thickness 0.15)
				)
				(justify left bottom)
				(hide yes)
			)
		)
		(property "License" "Apache-2.0"
			(at 256.54 304.8 0)
			(effects
				(font
					(size 1.27 1.27)
					(thickness 0.15)
				)
				(justify left bottom)
				(hide yes)
			)
		)
		(property "Author" "Antmicro"
			(at 259.08 304.8 0)
			(effects
				(font
					(size 1.27 1.27)
					(thickness 0.15)
				)
				(justify left bottom)
				(hide yes)
			)
		)
		(property "Val" "10k"
			(at 233.68 323.85 90)
			(effects
				(font
					(size 1.27 1.27)
					(thickness 0.15)
				)
				(justify right)
			)
		)
		(property "Tolerance" "1%"
			(at 241.3 304.8 0)
			(effects
				(font
					(size 1.27 1.27)
				)
				(justify left bottom)
				(hide yes)
			)
		)
		(pin "1"
		)
		(pin "2"
		)
		(instances
			(project "thunderbolt-gpu-adapter"
				(path ""
					(reference "R94")
					(unit 1)
				)
			)
		)
	)
	(symbol
		(lib_id "antmicroResistors0402:R_8k87_0402")
		(at 160.02 361.95 90)
		(unit 1)
		(exclude_from_sim no)
		(in_bom yes)
		(on_board yes)
		(dnp no)
		(fields_autoplaced yes)
		(property "Reference" "R37"
			(at 162.56 358.14 90)
			(effects
				(font
					(size 1.27 1.27)
					(thickness 0.15)
				)
				(justify right)
			)
		)
		(property "Value" "R_8k87_0402"
			(at 172.72 341.63 0)
			(effects
				(font
					(size 1.27 1.27)
					(thickness 0.15)
				)
				(justify left bottom)
				(hide yes)
			)
		)
		(property "Footprint" "antmicro-footprints:R_0402_1005Metric"
			(at 175.26 341.63 0)
			(effects
				(font
					(size 1.27 1.27)
					(thickness 0.15)
				)
				(justify left bottom)
				(hide yes)
			)
		)
		(property "Datasheet" "https://www.bourns.com/docs/product-datasheets/cr.pdf"
			(at 177.8 341.63 0)
			(effects
				(font
					(size 1.27 1.27)
					(thickness 0.15)
				)
				(justify left bottom)
				(hide yes)
			)
		)
		(property "Description" ""
			(at 160.02 361.95 0)
			(effects
				(font
					(size 1.27 1.27)
				)
				(hide yes)
			)
		)
		(property "MPN" "CR0402-FX-8871GLF"
			(at 180.34 341.63 0)
			(effects
				(font
					(size 1.27 1.27)
					(thickness 0.15)
				)
				(justify left bottom)
				(hide yes)
			)
		)
		(property "Manufacturer" "Bourns"
			(at 182.88 341.63 0)
			(effects
				(font
					(size 1.27 1.27)
					(thickness 0.15)
				)
				(justify left bottom)
				(hide yes)
			)
		)
		(property "License" "Apache-2.0"
			(at 185.42 341.63 0)
			(effects
				(font
					(size 1.27 1.27)
					(thickness 0.15)
				)
				(justify left bottom)
				(hide yes)
			)
		)
		(property "Val" "8k87"
			(at 162.56 360.68 90)
			(effects
				(font
					(size 1.27 1.27)
					(thickness 0.15)
				)
				(justify right)
			)
		)
		(property "Tolerance" "1%"
			(at 170.18 341.63 0)
			(effects
				(font
					(size 1.27 1.27)
				)
				(justify left bottom)
				(hide yes)
			)
		)
		(property "Author" "Antmicro"
			(at 187.96 341.63 0)
			(effects
				(font
					(size 1.27 1.27)
					(thickness 0.15)
				)
				(justify left bottom)
				(hide yes)
			)
		)
		(pin "1"
		)
		(pin "2"
		)
		(instances
			(project "thunderbolt-gpu-adapter"
				(path ""
					(reference "R37")
					(unit 1)
				)
			)
		)
	)
	(symbol
		(lib_id "antmicropower:GND")
		(at 111.76 229.87 0)
		(unit 1)
		(exclude_from_sim no)
		(in_bom yes)
		(on_board yes)
		(dnp no)
		(property "Reference" "#PWR0232"
			(at 111.76 236.22 0)
			(effects
				(font
					(size 1.27 1.27)
				)
				(hide yes)
			)
		)
		(property "Value" "GND"
			(at 109.855 234.315 0)
			(effects
				(font
					(size 1.27 1.27)
					(thickness 0.15)
				)
				(justify left bottom)
			)
		)
		(property "Footprint" ""
			(at 111.76 229.87 0)
			(effects
				(font
					(size 1.27 1.27)
					(thickness 0.15)
				)
				(justify left bottom)
				(hide yes)
			)
		)
		(property "Datasheet" ""
			(at 111.76 229.87 0)
			(effects
				(font
					(size 1.27 1.27)
					(thickness 0.15)
				)
				(justify left bottom)
				(hide yes)
			)
		)
		(property "Description" ""
			(at 111.76 229.87 0)
			(effects
				(font
					(size 1.27 1.27)
				)
				(hide yes)
			)
		)
		(property "Author" "Antmicro"
			(at 120.65 237.49 0)
			(effects
				(font
					(size 1.27 1.27)
					(thickness 0.15)
				)
				(justify left bottom)
				(hide yes)
			)
		)
		(property "License" "Apache-2.0"
			(at 120.65 240.03 0)
			(effects
				(font
					(size 1.27 1.27)
					(thickness 0.15)
				)
				(justify left bottom)
				(hide yes)
			)
		)
		(pin "1"
		)
		(instances
			(project "thunderbolt-gpu-adapter"
				(path ""
					(reference "#PWR0232")
					(unit 1)
				)
			)
		)
	)
	(symbol
		(lib_id "antmicropower:GND")
		(at 157.48 254 0)
		(unit 1)
		(exclude_from_sim no)
		(in_bom yes)
		(on_board yes)
		(dnp no)
		(property "Reference" "#PWR0235"
			(at 157.48 260.35 0)
			(effects
				(font
					(size 1.27 1.27)
				)
				(hide yes)
			)
		)
		(property "Value" "GND"
			(at 155.575 258.445 0)
			(effects
				(font
					(size 1.27 1.27)
					(thickness 0.15)
				)
				(justify left bottom)
			)
		)
		(property "Footprint" ""
			(at 157.48 254 0)
			(effects
				(font
					(size 1.27 1.27)
					(thickness 0.15)
				)
				(justify left bottom)
				(hide yes)
			)
		)
		(property "Datasheet" ""
			(at 157.48 254 0)
			(effects
				(font
					(size 1.27 1.27)
					(thickness 0.15)
				)
				(justify left bottom)
				(hide yes)
			)
		)
		(property "Description" ""
			(at 157.48 254 0)
			(effects
				(font
					(size 1.27 1.27)
				)
				(hide yes)
			)
		)
		(property "Author" "Antmicro"
			(at 166.37 261.62 0)
			(effects
				(font
					(size 1.27 1.27)
					(thickness 0.15)
				)
				(justify left bottom)
				(hide yes)
			)
		)
		(property "License" "Apache-2.0"
			(at 166.37 264.16 0)
			(effects
				(font
					(size 1.27 1.27)
					(thickness 0.15)
				)
				(justify left bottom)
				(hide yes)
			)
		)
		(pin "1"
		)
		(instances
			(project "thunderbolt-gpu-adapter"
				(path ""
					(reference "#PWR0235")
					(unit 1)
				)
			)
		)
	)
	(symbol
		(lib_id "antmicropower:GND")
		(at 45.72 207.01 0)
		(unit 1)
		(exclude_from_sim no)
		(in_bom yes)
		(on_board yes)
		(dnp no)
		(property "Reference" "#PWR038"
			(at 45.72 213.36 0)
			(effects
				(font
					(size 1.27 1.27)
				)
				(hide yes)
			)
		)
		(property "Value" "GND"
			(at 43.815 211.455 0)
			(effects
				(font
					(size 1.27 1.27)
					(thickness 0.15)
				)
				(justify left bottom)
			)
		)
		(property "Footprint" ""
			(at 45.72 207.01 0)
			(effects
				(font
					(size 1.27 1.27)
					(thickness 0.15)
				)
				(justify left bottom)
				(hide yes)
			)
		)
		(property "Datasheet" ""
			(at 45.72 207.01 0)
			(effects
				(font
					(size 1.27 1.27)
					(thickness 0.15)
				)
				(justify left bottom)
				(hide yes)
			)
		)
		(property "Description" ""
			(at 45.72 207.01 0)
			(effects
				(font
					(size 1.27 1.27)
				)
				(hide yes)
			)
		)
		(property "Author" "Antmicro"
			(at 54.61 214.63 0)
			(effects
				(font
					(size 1.27 1.27)
					(thickness 0.15)
				)
				(justify left bottom)
				(hide yes)
			)
		)
		(property "License" "Apache-2.0"
			(at 54.61 217.17 0)
			(effects
				(font
					(size 1.27 1.27)
					(thickness 0.15)
				)
				(justify left bottom)
				(hide yes)
			)
		)
		(pin "1"
		)
		(instances
			(project "thunderbolt-gpu-adapter"
				(path ""
					(reference "#PWR038")
					(unit 1)
				)
			)
		)
	)
	(symbol
		(lib_id "antmicroCapacitors0402:C_220n_0402")
		(at 111.76 243.84 270)
		(mirror x)
		(unit 1)
		(exclude_from_sim no)
		(in_bom yes)
		(on_board yes)
		(dnp no)
		(fields_autoplaced yes)
		(property "Reference" "C16"
			(at 109.22 240.0236 90)
			(effects
				(font
					(size 1.27 1.27)
					(thickness 0.15)
				)
				(justify right)
			)
		)
		(property "Value" "C_220n_0402"
			(at 101.6 223.52 0)
			(effects
				(font
					(size 1.27 1.27)
					(thickness 0.15)
				)
				(justify left bottom)
				(hide yes)
			)
		)
		(property "Footprint" "antmicro-footprints:C_0402_1005Metric"
			(at 99.06 223.52 0)
			(effects
				(font
					(size 1.27 1.27)
					(thickness 0.15)
				)
				(justify left bottom)
				(hide yes)
			)
		)
		(property "Datasheet" "https://www.yageo.com/en/Chart/Download/pdf/CC0402KRX5R6BB224"
			(at 96.52 223.52 0)
			(effects
				(font
					(size 1.27 1.27)
					(thickness 0.15)
				)
				(justify left bottom)
				(hide yes)
			)
		)
		(property "Description" ""
			(at 111.76 243.84 0)
			(effects
				(font
					(size 1.27 1.27)
				)
				(hide yes)
			)
		)
		(property "MPN" "CC0402KRX5R6BB224"
			(at 93.98 223.52 0)
			(effects
				(font
					(size 1.27 1.27)
					(thickness 0.15)
				)
				(justify left bottom)
				(hide yes)
			)
		)
		(property "Manufacturer" "YAGEO"
			(at 91.44 223.52 0)
			(effects
				(font
					(size 1.27 1.27)
					(thickness 0.15)
				)
				(justify left bottom)
				(hide yes)
			)
		)
		(property "License" "Apache-2.0"
			(at 88.9 223.52 0)
			(effects
				(font
					(size 1.27 1.27)
					(thickness 0.15)
				)
				(justify left bottom)
				(hide yes)
			)
		)
		(property "Val" "220n"
			(at 109.22 242.5636 90)
			(effects
				(font
					(size 1.27 1.27)
					(thickness 0.15)
				)
				(justify right)
			)
		)
		(property "Voltage" ""
			(at 83.82 223.52 0)
			(effects
				(font
					(size 1.27 1.27)
				)
				(justify left bottom)
				(hide yes)
			)
		)
		(property "Dielectric" ""
			(at 81.28 223.52 0)
			(effects
				(font
					(size 1.27 1.27)
				)
				(justify left bottom)
				(hide yes)
			)
		)
		(property "Author" "Antmicro"
			(at 86.36 223.52 0)
			(effects
				(font
					(size 1.27 1.27)
					(thickness 0.15)
				)
				(justify left bottom)
				(hide yes)
			)
		)
		(pin "1"
		)
		(pin "2"
		)
		(instances
			(project "thunderbolt-gpu-adapter"
				(path ""
					(reference "C16")
					(unit 1)
				)
			)
		)
	)
	(symbol
		(lib_id "antmicroResistors0402:R_100k_0402")
		(at 234.95 71.12 90)
		(unit 1)
		(exclude_from_sim no)
		(in_bom yes)
		(on_board yes)
		(dnp no)
		(fields_autoplaced yes)
		(property "Reference" "R122"
			(at 237.49 67.31 90)
			(effects
				(font
					(size 1.27 1.27)
					(thickness 0.15)
				)
				(justify right)
			)
		)
		(property "Value" "R_100k_0402"
			(at 247.65 50.8 0)
			(effects
				(font
					(size 1.27 1.27)
					(thickness 0.15)
				)
				(justify left bottom)
				(hide yes)
			)
		)
		(property "Footprint" "antmicro-footprints:R_0402_1005Metric"
			(at 250.19 50.8 0)
			(effects
				(font
					(size 1.27 1.27)
					(thickness 0.15)
				)
				(justify left bottom)
				(hide yes)
			)
		)
		(property "Datasheet" "https://www.bourns.com/docs/product-datasheets/cr.pdf"
			(at 252.73 50.8 0)
			(effects
				(font
					(size 1.27 1.27)
					(thickness 0.15)
				)
				(justify left bottom)
				(hide yes)
			)
		)
		(property "Description" ""
			(at 234.95 71.12 0)
			(effects
				(font
					(size 1.27 1.27)
				)
				(hide yes)
			)
		)
		(property "MPN" "CR0402-FX-1003GLF"
			(at 255.27 50.8 0)
			(effects
				(font
					(size 1.27 1.27)
					(thickness 0.15)
				)
				(justify left bottom)
				(hide yes)
			)
		)
		(property "Manufacturer" "Bourns"
			(at 257.81 50.8 0)
			(effects
				(font
					(size 1.27 1.27)
					(thickness 0.15)
				)
				(justify left bottom)
				(hide yes)
			)
		)
		(property "License" "Apache-2.0"
			(at 260.35 50.8 0)
			(effects
				(font
					(size 1.27 1.27)
					(thickness 0.15)
				)
				(justify left bottom)
				(hide yes)
			)
		)
		(property "Author" "Antmicro"
			(at 262.89 50.8 0)
			(effects
				(font
					(size 1.27 1.27)
					(thickness 0.15)
				)
				(justify left bottom)
				(hide yes)
			)
		)
		(property "Val" "100k"
			(at 237.49 69.85 90)
			(effects
				(font
					(size 1.27 1.27)
					(thickness 0.15)
				)
				(justify right)
			)
		)
		(property "Tolerance" "1%"
			(at 245.11 50.8 0)
			(effects
				(font
					(size 1.27 1.27)
				)
				(justify left bottom)
				(hide yes)
			)
		)
		(pin "1"
		)
		(pin "2"
		)
		(instances
			(project "thunderbolt-gpu-adapter"
				(path ""
					(reference "R122")
					(unit 1)
				)
			)
		)
	)
	(symbol
		(lib_id "antmicropower:GND")
		(at 229.87 364.49 0)
		(unit 1)
		(exclude_from_sim no)
		(in_bom yes)
		(on_board yes)
		(dnp no)
		(fields_autoplaced yes)
		(property "Reference" "#PWR0217"
			(at 229.87 370.84 0)
			(effects
				(font
					(size 1.27 1.27)
				)
				(hide yes)
			)
		)
		(property "Value" "GND"
			(at 229.87 368.3 0)
			(effects
				(font
					(size 1.27 1.27)
				)
			)
		)
		(property "Footprint" ""
			(at 229.87 364.49 0)
			(effects
				(font
					(size 1.27 1.27)
				)
				(hide yes)
			)
		)
		(property "Datasheet" ""
			(at 229.87 364.49 0)
			(effects
				(font
					(size 1.27 1.27)
				)
				(hide yes)
			)
		)
		(property "Description" ""
			(at 229.87 364.49 0)
			(effects
				(font
					(size 1.27 1.27)
				)
				(hide yes)
			)
		)
		(property "Author" "Antmicro"
			(at 238.76 372.11 0)
			(effects
				(font
					(size 1.27 1.27)
					(thickness 0.15)
				)
				(justify left bottom)
				(hide yes)
			)
		)
		(property "License" "Apache-2.0"
			(at 238.76 374.65 0)
			(effects
				(font
					(size 1.27 1.27)
					(thickness 0.15)
				)
				(justify left bottom)
				(hide yes)
			)
		)
		(pin "1"
		)
		(instances
			(project "thunderbolt-gpu-adapter"
				(path ""
					(reference "#PWR0217")
					(unit 1)
				)
			)
		)
	)
	(symbol
		(lib_id "antmicroPMICORControllersIdealDiodes:DZDH0401DW")
		(at 232.41 313.69 0)
		(unit 1)
		(exclude_from_sim no)
		(in_bom yes)
		(on_board yes)
		(dnp no)
		(fields_autoplaced yes)
		(property "Reference" "Q4"
			(at 240.665 307.34 0)
			(effects
				(font
					(size 1.524 1.524)
				)
			)
		)
		(property "Value" "DZDH0401DW"
			(at 262.89 321.31 0)
			(effects
				(font
					(size 1.27 1.27)
					(thickness 0.15)
				)
				(justify left bottom)
				(hide yes)
			)
		)
		(property "Footprint" "antmicro-footprints:SOT-363"
			(at 262.89 323.85 0)
			(effects
				(font
					(size 1.27 1.27)
					(thickness 0.15)
				)
				(justify left bottom)
				(hide yes)
			)
		)
		(property "Datasheet" "https://www.mouser.com/datasheet/2/115/DIOD_S_A0011803041_1-2543705.pdf"
			(at 262.89 326.39 0)
			(effects
				(font
					(size 1.27 1.27)
					(thickness 0.15)
				)
				(justify left bottom)
				(hide yes)
			)
		)
		(property "Description" ""
			(at 232.41 313.69 0)
			(effects
				(font
					(size 1.27 1.27)
				)
				(hide yes)
			)
		)
		(property "MPN" "DZDH0401DW"
			(at 240.665 309.88 0)
			(effects
				(font
					(size 1.27 1.27)
					(thickness 0.15)
				)
			)
		)
		(property "Manufacturer" "Diodes Incorporated"
			(at 262.89 331.47 0)
			(effects
				(font
					(size 1.27 1.27)
					(thickness 0.15)
				)
				(justify left bottom)
				(hide yes)
			)
		)
		(property "Author" "Antmicro"
			(at 262.89 334.01 0)
			(effects
				(font
					(size 1.27 1.27)
					(thickness 0.15)
				)
				(justify left bottom)
				(hide yes)
			)
		)
		(property "License" "Apache-2.0"
			(at 262.89 336.55 0)
			(effects
				(font
					(size 1.27 1.27)
					(thickness 0.15)
				)
				(justify left bottom)
				(hide yes)
			)
		)
		(pin "2"
		)
		(pin "3"
		)
		(pin "4"
		)
		(pin "6"
		)
		(instances
			(project "thunderbolt-gpu-adapter"
				(path ""
					(reference "Q4")
					(unit 1)
				)
			)
		)
	)
	(symbol
		(lib_id "antmicroCapacitors0402:C_10u_0402")
		(at 64.77 67.31 0)
		(unit 1)
		(exclude_from_sim no)
		(in_bom yes)
		(on_board yes)
		(dnp no)
		(property "Reference" "C23"
			(at 64.77 68.58 0)
			(effects
				(font
					(size 1.27 1.27)
					(thickness 0.15)
				)
			)
		)
		(property "Value" "C_10u_0402"
			(at 85.09 77.47 0)
			(effects
				(font
					(size 1.27 1.27)
					(thickness 0.15)
				)
				(justify left bottom)
				(hide yes)
			)
		)
		(property "Footprint" "antmicro-footprints:C_0402_1005Metric"
			(at 85.09 80.01 0)
			(effects
				(font
					(size 1.27 1.27)
					(thickness 0.15)
				)
				(justify left bottom)
				(hide yes)
			)
		)
		(property "Datasheet" "https://www.yageo.com/en/Chart/Download/pdf/CC0402MRX5R5BB106"
			(at 85.09 82.55 0)
			(effects
				(font
					(size 1.27 1.27)
					(thickness 0.15)
				)
				(justify left bottom)
				(hide yes)
			)
		)
		(property "Description" ""
			(at 64.77 67.31 0)
			(effects
				(font
					(size 1.27 1.27)
				)
				(hide yes)
			)
		)
		(property "MPN" "CC0402MRX5R5BB106"
			(at 85.09 85.09 0)
			(effects
				(font
					(size 1.27 1.27)
					(thickness 0.15)
				)
				(justify left bottom)
				(hide yes)
			)
		)
		(property "Manufacturer" "YAGEO"
			(at 85.09 87.63 0)
			(effects
				(font
					(size 1.27 1.27)
					(thickness 0.15)
				)
				(justify left bottom)
				(hide yes)
			)
		)
		(property "License" "Apache-2.0"
			(at 85.09 90.17 0)
			(effects
				(font
					(size 1.27 1.27)
					(thickness 0.15)
				)
				(justify left bottom)
				(hide yes)
			)
		)
		(property "Val" "10u"
			(at 69.85 68.58 0)
			(effects
				(font
					(size 1.27 1.27)
					(thickness 0.15)
				)
			)
		)
		(property "Voltage" ""
			(at 85.09 95.25 0)
			(effects
				(font
					(size 1.27 1.27)
				)
				(justify left bottom)
				(hide yes)
			)
		)
		(property "Dielectric" ""
			(at 85.09 97.79 0)
			(effects
				(font
					(size 1.27 1.27)
				)
				(justify left bottom)
				(hide yes)
			)
		)
		(property "Author" "Antmicro"
			(at 85.09 92.71 0)
			(effects
				(font
					(size 1.27 1.27)
					(thickness 0.15)
				)
				(justify left bottom)
				(hide yes)
			)
		)
		(pin "1"
		)
		(pin "2"
		)
		(instances
			(project "thunderbolt-gpu-adapter"
				(path ""
					(reference "C23")
					(unit 1)
				)
			)
		)
	)
	(symbol
		(lib_id "antmicropower:GND")
		(at 148.59 64.77 0)
		(unit 1)
		(exclude_from_sim no)
		(in_bom yes)
		(on_board yes)
		(dnp no)
		(property "Reference" "#PWR052"
			(at 148.59 71.12 0)
			(effects
				(font
					(size 1.27 1.27)
				)
				(hide yes)
			)
		)
		(property "Value" "GND"
			(at 148.59 68.58 0)
			(effects
				(font
					(size 1.27 1.27)
				)
			)
		)
		(property "Footprint" ""
			(at 148.59 64.77 0)
			(effects
				(font
					(size 1.27 1.27)
				)
				(hide yes)
			)
		)
		(property "Datasheet" ""
			(at 148.59 64.77 0)
			(effects
				(font
					(size 1.27 1.27)
				)
				(hide yes)
			)
		)
		(property "Description" ""
			(at 148.59 64.77 0)
			(effects
				(font
					(size 1.27 1.27)
				)
				(hide yes)
			)
		)
		(property "Author" "Antmicro"
			(at 157.48 72.39 0)
			(effects
				(font
					(size 1.27 1.27)
					(thickness 0.15)
				)
				(justify left bottom)
				(hide yes)
			)
		)
		(property "License" "Apache-2.0"
			(at 157.48 74.93 0)
			(effects
				(font
					(size 1.27 1.27)
					(thickness 0.15)
				)
				(justify left bottom)
				(hide yes)
			)
		)
		(pin "1"
		)
		(instances
			(project "thunderbolt-gpu-adapter"
				(path ""
					(reference "#PWR052")
					(unit 1)
				)
			)
		)
	)
	(symbol
		(lib_id "antmicroCapacitors0603:C_22u_16V_0603")
		(at 212.09 210.82 90)
		(unit 1)
		(exclude_from_sim no)
		(in_bom yes)
		(on_board yes)
		(dnp no)
		(fields_autoplaced yes)
		(property "Reference" "C43"
			(at 214.63 207.0036 90)
			(effects
				(font
					(size 1.27 1.27)
					(thickness 0.15)
				)
				(justify right)
			)
		)
		(property "Value" "C_22u_16V_0603"
			(at 222.25 190.5 0)
			(effects
				(font
					(size 1.27 1.27)
					(thickness 0.15)
				)
				(justify left bottom)
				(hide yes)
			)
		)
		(property "Footprint" "antmicro-footprints:C_0603_1608Metric"
			(at 224.79 190.5 0)
			(effects
				(font
					(size 1.27 1.27)
					(thickness 0.15)
				)
				(justify left bottom)
				(hide yes)
			)
		)
		(property "Datasheet" "https://product.samsungsem.com/mlcc/CL10A226MO7JZN.do"
			(at 227.33 190.5 0)
			(effects
				(font
					(size 1.27 1.27)
					(thickness 0.15)
				)
				(justify left bottom)
				(hide yes)
			)
		)
		(property "Description" ""
			(at 212.09 210.82 0)
			(effects
				(font
					(size 1.27 1.27)
				)
				(hide yes)
			)
		)
		(property "MPN" "CL10A226MO7JZNC"
			(at 229.87 190.5 0)
			(effects
				(font
					(size 1.27 1.27)
					(thickness 0.15)
				)
				(justify left bottom)
				(hide yes)
			)
		)
		(property "Manufacturer" "Samsung Electro-Mechanics"
			(at 232.41 190.5 0)
			(effects
				(font
					(size 1.27 1.27)
					(thickness 0.15)
				)
				(justify left bottom)
				(hide yes)
			)
		)
		(property "License" "Apache-2.0"
			(at 234.95 190.5 0)
			(effects
				(font
					(size 1.27 1.27)
					(thickness 0.15)
				)
				(justify left bottom)
				(hide yes)
			)
		)
		(property "Val" "22u"
			(at 214.63 209.5436 90)
			(effects
				(font
					(size 1.27 1.27)
					(thickness 0.15)
				)
				(justify right)
			)
		)
		(property "Voltage" "16V"
			(at 240.03 190.5 0)
			(effects
				(font
					(size 1.27 1.27)
				)
				(justify left bottom)
				(hide yes)
			)
		)
		(property "Dielectric" ""
			(at 242.57 190.5 0)
			(effects
				(font
					(size 1.27 1.27)
				)
				(justify left bottom)
				(hide yes)
			)
		)
		(property "Author" "Antmicro"
			(at 237.49 190.5 0)
			(effects
				(font
					(size 1.27 1.27)
					(thickness 0.15)
				)
				(justify left bottom)
				(hide yes)
			)
		)
		(pin "1"
		)
		(pin "2"
		)
		(instances
			(project "thunderbolt-gpu-adapter"
				(path ""
					(reference "C43")
					(unit 1)
				)
			)
		)
	)
	(symbol
		(lib_id "antmicroCapacitorsmisc:C_22u_1206_35V")
		(at 83.82 337.82 90)
		(unit 1)
		(exclude_from_sim no)
		(in_bom yes)
		(on_board yes)
		(dnp no)
		(fields_autoplaced yes)
		(property "Reference" "C17"
			(at 86.36 334.0036 90)
			(effects
				(font
					(size 1.27 1.27)
					(thickness 0.15)
				)
				(justify right)
			)
		)
		(property "Value" "C_22u_1206_35V"
			(at 93.98 317.5 0)
			(effects
				(font
					(size 1.27 1.27)
					(thickness 0.15)
				)
				(justify left bottom)
				(hide yes)
			)
		)
		(property "Footprint" "antmicro-footprints:C_1206_3216Metric"
			(at 96.52 317.5 0)
			(effects
				(font
					(size 1.27 1.27)
					(thickness 0.15)
				)
				(justify left bottom)
				(hide yes)
			)
		)
		(property "Datasheet" "https://product.tdk.com/en/search/capacitor/ceramic/mlcc/info?part_no=3216X5R1V226M160AC"
			(at 99.06 317.5 0)
			(effects
				(font
					(size 1.27 1.27)
					(thickness 0.15)
				)
				(justify left bottom)
				(hide yes)
			)
		)
		(property "Description" ""
			(at 83.82 337.82 0)
			(effects
				(font
					(size 1.27 1.27)
				)
				(hide yes)
			)
		)
		(property "MPN" "3216X5R1V226M160AC"
			(at 101.6 317.5 0)
			(effects
				(font
					(size 1.27 1.27)
					(thickness 0.15)
				)
				(justify left bottom)
				(hide yes)
			)
		)
		(property "Manufacturer" "TDK"
			(at 104.14 317.5 0)
			(effects
				(font
					(size 1.27 1.27)
					(thickness 0.15)
				)
				(justify left bottom)
				(hide yes)
			)
		)
		(property "License" "Apache-2.0"
			(at 106.68 317.5 0)
			(effects
				(font
					(size 1.27 1.27)
					(thickness 0.15)
				)
				(justify left bottom)
				(hide yes)
			)
		)
		(property "Val" "22u"
			(at 86.36 336.5436 90)
			(effects
				(font
					(size 1.27 1.27)
					(thickness 0.15)
				)
				(justify right)
			)
		)
		(property "Voltage" "35V"
			(at 111.76 317.5 0)
			(effects
				(font
					(size 1.27 1.27)
				)
				(justify left bottom)
				(hide yes)
			)
		)
		(property "Dielectric" ""
			(at 114.3 317.5 0)
			(effects
				(font
					(size 1.27 1.27)
				)
				(justify left bottom)
				(hide yes)
			)
		)
		(property "Author" "Antmicro"
			(at 109.22 317.5 0)
			(effects
				(font
					(size 1.27 1.27)
					(thickness 0.15)
				)
				(justify left bottom)
				(hide yes)
			)
		)
		(pin "1"
		)
		(pin "2"
		)
		(instances
			(project "thunderbolt-gpu-adapter"
				(path ""
					(reference "C17")
					(unit 1)
				)
			)
		)
	)
	(symbol
		(lib_id "antmicroResistors0402:R_100k_0402")
		(at 121.92 359.41 0)
		(mirror x)
		(unit 1)
		(exclude_from_sim no)
		(in_bom yes)
		(on_board yes)
		(dnp no)
		(fields_autoplaced yes)
		(property "Reference" "R23"
			(at 124.46 363.22 0)
			(effects
				(font
					(size 1.27 1.27)
					(thickness 0.15)
				)
			)
		)
		(property "Value" "R_100k_0402"
			(at 142.24 346.71 0)
			(effects
				(font
					(size 1.27 1.27)
					(thickness 0.15)
				)
				(justify left bottom)
				(hide yes)
			)
		)
		(property "Footprint" "antmicro-footprints:R_0402_1005Metric"
			(at 142.24 344.17 0)
			(effects
				(font
					(size 1.27 1.27)
					(thickness 0.15)
				)
				(justify left bottom)
				(hide yes)
			)
		)
		(property "Datasheet" "https://www.bourns.com/docs/product-datasheets/cr.pdf"
			(at 142.24 341.63 0)
			(effects
				(font
					(size 1.27 1.27)
					(thickness 0.15)
				)
				(justify left bottom)
				(hide yes)
			)
		)
		(property "Description" ""
			(at 121.92 359.41 0)
			(effects
				(font
					(size 1.27 1.27)
				)
				(hide yes)
			)
		)
		(property "MPN" "CR0402-FX-1003GLF"
			(at 142.24 339.09 0)
			(effects
				(font
					(size 1.27 1.27)
					(thickness 0.15)
				)
				(justify left bottom)
				(hide yes)
			)
		)
		(property "Manufacturer" "Bourns"
			(at 142.24 336.55 0)
			(effects
				(font
					(size 1.27 1.27)
					(thickness 0.15)
				)
				(justify left bottom)
				(hide yes)
			)
		)
		(property "License" "Apache-2.0"
			(at 142.24 334.01 0)
			(effects
				(font
					(size 1.27 1.27)
					(thickness 0.15)
				)
				(justify left bottom)
				(hide yes)
			)
		)
		(property "Val" "100k"
			(at 124.46 365.76 0)
			(effects
				(font
					(size 1.27 1.27)
					(thickness 0.15)
				)
			)
		)
		(property "Tolerance" "1%"
			(at 142.24 349.25 0)
			(effects
				(font
					(size 1.27 1.27)
				)
				(justify left bottom)
				(hide yes)
			)
		)
		(property "Author" "Antmicro"
			(at 142.24 331.47 0)
			(effects
				(font
					(size 1.27 1.27)
					(thickness 0.15)
				)
				(justify left bottom)
				(hide yes)
			)
		)
		(pin "1"
		)
		(pin "2"
		)
		(instances
			(project "thunderbolt-gpu-adapter"
				(path ""
					(reference "R23")
					(unit 1)
				)
			)
		)
	)
	(symbol
		(lib_id "antmicroCapacitors0402:C_220n_0402")
		(at 121.92 344.17 0)
		(unit 1)
		(exclude_from_sim no)
		(in_bom yes)
		(on_board yes)
		(dnp no)
		(fields_autoplaced yes)
		(property "Reference" "C27"
			(at 124.4663 337.82 0)
			(effects
				(font
					(size 1.27 1.27)
					(thickness 0.15)
				)
			)
		)
		(property "Value" "C_220n_0402"
			(at 142.24 354.33 0)
			(effects
				(font
					(size 1.27 1.27)
					(thickness 0.15)
				)
				(justify left bottom)
				(hide yes)
			)
		)
		(property "Footprint" "antmicro-footprints:C_0402_1005Metric"
			(at 142.24 356.87 0)
			(effects
				(font
					(size 1.27 1.27)
					(thickness 0.15)
				)
				(justify left bottom)
				(hide yes)
			)
		)
		(property "Datasheet" "https://www.yageo.com/en/Chart/Download/pdf/CC0402KRX5R6BB224"
			(at 142.24 359.41 0)
			(effects
				(font
					(size 1.27 1.27)
					(thickness 0.15)
				)
				(justify left bottom)
				(hide yes)
			)
		)
		(property "Description" ""
			(at 121.92 344.17 0)
			(effects
				(font
					(size 1.27 1.27)
				)
				(hide yes)
			)
		)
		(property "MPN" "CC0402KRX5R6BB224"
			(at 142.24 361.95 0)
			(effects
				(font
					(size 1.27 1.27)
					(thickness 0.15)
				)
				(justify left bottom)
				(hide yes)
			)
		)
		(property "Manufacturer" "YAGEO"
			(at 142.24 364.49 0)
			(effects
				(font
					(size 1.27 1.27)
					(thickness 0.15)
				)
				(justify left bottom)
				(hide yes)
			)
		)
		(property "License" "Apache-2.0"
			(at 142.24 367.03 0)
			(effects
				(font
					(size 1.27 1.27)
					(thickness 0.15)
				)
				(justify left bottom)
				(hide yes)
			)
		)
		(property "Val" "220n"
			(at 124.4663 340.36 0)
			(effects
				(font
					(size 1.27 1.27)
					(thickness 0.15)
				)
			)
		)
		(property "Voltage" ""
			(at 142.24 372.11 0)
			(effects
				(font
					(size 1.27 1.27)
				)
				(justify left bottom)
				(hide yes)
			)
		)
		(property "Dielectric" ""
			(at 142.24 374.65 0)
			(effects
				(font
					(size 1.27 1.27)
				)
				(justify left bottom)
				(hide yes)
			)
		)
		(property "Author" "Antmicro"
			(at 142.24 369.57 0)
			(effects
				(font
					(size 1.27 1.27)
					(thickness 0.15)
				)
				(justify left bottom)
				(hide yes)
			)
		)
		(pin "1"
		)
		(pin "2"
		)
		(instances
			(project "thunderbolt-gpu-adapter"
				(path ""
					(reference "C27")
					(unit 1)
				)
			)
		)
	)
	(symbol
		(lib_id "antmicroCapacitors0402:C_100n_0402")
		(at 255.27 127 270)
		(mirror x)
		(unit 1)
		(exclude_from_sim no)
		(in_bom yes)
		(on_board yes)
		(dnp no)
		(property "Reference" "C133"
			(at 256.54 123.19 90)
			(effects
				(font
					(size 1.27 1.27)
					(thickness 0.15)
				)
				(justify left)
			)
		)
		(property "Value" "C_100n_0402"
			(at 245.11 106.68 0)
			(effects
				(font
					(size 1.27 1.27)
					(thickness 0.15)
				)
				(justify left bottom)
				(hide yes)
			)
		)
		(property "Footprint" "antmicro-footprints:C_0402_1005Metric"
			(at 242.57 106.68 0)
			(effects
				(font
					(size 1.27 1.27)
					(thickness 0.15)
				)
				(justify left bottom)
				(hide yes)
			)
		)
		(property "Datasheet" "https://www.murata.com/products/productdetail?partno=GRM155R61H104KE14%23"
			(at 240.03 106.68 0)
			(effects
				(font
					(size 1.27 1.27)
					(thickness 0.15)
				)
				(justify left bottom)
				(hide yes)
			)
		)
		(property "Description" ""
			(at 255.27 127 0)
			(effects
				(font
					(size 1.27 1.27)
				)
				(hide yes)
			)
		)
		(property "MPN" "GRM155R61H104KE14D"
			(at 237.49 106.68 0)
			(effects
				(font
					(size 1.27 1.27)
					(thickness 0.15)
				)
				(justify left bottom)
				(hide yes)
			)
		)
		(property "Manufacturer" "Murata"
			(at 234.95 106.68 0)
			(effects
				(font
					(size 1.27 1.27)
					(thickness 0.15)
				)
				(justify left bottom)
				(hide yes)
			)
		)
		(property "License" "Apache-2.0"
			(at 232.41 106.68 0)
			(effects
				(font
					(size 1.27 1.27)
					(thickness 0.15)
				)
				(justify left bottom)
				(hide yes)
			)
		)
		(property "Val" "100n"
			(at 256.54 125.73 90)
			(effects
				(font
					(size 1.27 1.27)
					(thickness 0.15)
				)
				(justify left)
			)
		)
		(property "Voltage" "50V"
			(at 227.33 106.68 0)
			(effects
				(font
					(size 1.27 1.27)
				)
				(justify left bottom)
				(hide yes)
			)
		)
		(property "Dielectric" "X5R"
			(at 224.79 106.68 0)
			(effects
				(font
					(size 1.27 1.27)
				)
				(justify left bottom)
				(hide yes)
			)
		)
		(property "Author" "Antmicro"
			(at 229.87 106.68 0)
			(effects
				(font
					(size 1.27 1.27)
					(thickness 0.15)
				)
				(justify left bottom)
				(hide yes)
			)
		)
		(pin "1"
		)
		(pin "2"
		)
		(instances
			(project "thunderbolt-gpu-adapter"
				(path ""
					(reference "C133")
					(unit 1)
				)
			)
		)
	)
	(symbol
		(lib_id "antmicroResistors0402:R_100k_0402")
		(at 237.49 91.44 90)
		(unit 1)
		(exclude_from_sim no)
		(in_bom yes)
		(on_board yes)
		(dnp no)
		(fields_autoplaced yes)
		(property "Reference" "R125"
			(at 240.03 87.63 90)
			(effects
				(font
					(size 1.27 1.27)
					(thickness 0.15)
				)
				(justify right)
			)
		)
		(property "Value" "R_100k_0402"
			(at 250.19 71.12 0)
			(effects
				(font
					(size 1.27 1.27)
					(thickness 0.15)
				)
				(justify left bottom)
				(hide yes)
			)
		)
		(property "Footprint" "antmicro-footprints:R_0402_1005Metric"
			(at 252.73 71.12 0)
			(effects
				(font
					(size 1.27 1.27)
					(thickness 0.15)
				)
				(justify left bottom)
				(hide yes)
			)
		)
		(property "Datasheet" "https://www.bourns.com/docs/product-datasheets/cr.pdf"
			(at 255.27 71.12 0)
			(effects
				(font
					(size 1.27 1.27)
					(thickness 0.15)
				)
				(justify left bottom)
				(hide yes)
			)
		)
		(property "Description" ""
			(at 237.49 91.44 0)
			(effects
				(font
					(size 1.27 1.27)
				)
				(hide yes)
			)
		)
		(property "MPN" "CR0402-FX-1003GLF"
			(at 257.81 71.12 0)
			(effects
				(font
					(size 1.27 1.27)
					(thickness 0.15)
				)
				(justify left bottom)
				(hide yes)
			)
		)
		(property "Manufacturer" "Bourns"
			(at 260.35 71.12 0)
			(effects
				(font
					(size 1.27 1.27)
					(thickness 0.15)
				)
				(justify left bottom)
				(hide yes)
			)
		)
		(property "License" "Apache-2.0"
			(at 262.89 71.12 0)
			(effects
				(font
					(size 1.27 1.27)
					(thickness 0.15)
				)
				(justify left bottom)
				(hide yes)
			)
		)
		(property "Author" "Antmicro"
			(at 265.43 71.12 0)
			(effects
				(font
					(size 1.27 1.27)
					(thickness 0.15)
				)
				(justify left bottom)
				(hide yes)
			)
		)
		(property "Val" "100k"
			(at 240.03 90.17 90)
			(effects
				(font
					(size 1.27 1.27)
					(thickness 0.15)
				)
				(justify right)
			)
		)
		(property "Tolerance" "1%"
			(at 247.65 71.12 0)
			(effects
				(font
					(size 1.27 1.27)
				)
				(justify left bottom)
				(hide yes)
			)
		)
		(pin "1"
		)
		(pin "2"
		)
		(instances
			(project "thunderbolt-gpu-adapter"
				(path ""
					(reference "R125")
					(unit 1)
				)
			)
		)
	)
	(symbol
		(lib_id "antmicroCapacitors0603:C_22u_16V_0603")
		(at 220.98 210.82 90)
		(unit 1)
		(exclude_from_sim no)
		(in_bom yes)
		(on_board yes)
		(dnp no)
		(fields_autoplaced yes)
		(property "Reference" "C46"
			(at 223.52 207.0036 90)
			(effects
				(font
					(size 1.27 1.27)
					(thickness 0.15)
				)
				(justify right)
			)
		)
		(property "Value" "C_22u_16V_0603"
			(at 231.14 190.5 0)
			(effects
				(font
					(size 1.27 1.27)
					(thickness 0.15)
				)
				(justify left bottom)
				(hide yes)
			)
		)
		(property "Footprint" "antmicro-footprints:C_0603_1608Metric"
			(at 233.68 190.5 0)
			(effects
				(font
					(size 1.27 1.27)
					(thickness 0.15)
				)
				(justify left bottom)
				(hide yes)
			)
		)
		(property "Datasheet" "https://product.samsungsem.com/mlcc/CL10A226MO7JZN.do"
			(at 236.22 190.5 0)
			(effects
				(font
					(size 1.27 1.27)
					(thickness 0.15)
				)
				(justify left bottom)
				(hide yes)
			)
		)
		(property "Description" ""
			(at 220.98 210.82 0)
			(effects
				(font
					(size 1.27 1.27)
				)
				(hide yes)
			)
		)
		(property "MPN" "CL10A226MO7JZNC"
			(at 238.76 190.5 0)
			(effects
				(font
					(size 1.27 1.27)
					(thickness 0.15)
				)
				(justify left bottom)
				(hide yes)
			)
		)
		(property "Manufacturer" "Samsung Electro-Mechanics"
			(at 241.3 190.5 0)
			(effects
				(font
					(size 1.27 1.27)
					(thickness 0.15)
				)
				(justify left bottom)
				(hide yes)
			)
		)
		(property "License" "Apache-2.0"
			(at 243.84 190.5 0)
			(effects
				(font
					(size 1.27 1.27)
					(thickness 0.15)
				)
				(justify left bottom)
				(hide yes)
			)
		)
		(property "Val" "22u"
			(at 223.52 209.5436 90)
			(effects
				(font
					(size 1.27 1.27)
					(thickness 0.15)
				)
				(justify right)
			)
		)
		(property "Voltage" "16V"
			(at 248.92 190.5 0)
			(effects
				(font
					(size 1.27 1.27)
				)
				(justify left bottom)
				(hide yes)
			)
		)
		(property "Dielectric" ""
			(at 251.46 190.5 0)
			(effects
				(font
					(size 1.27 1.27)
				)
				(justify left bottom)
				(hide yes)
			)
		)
		(property "Author" "Antmicro"
			(at 246.38 190.5 0)
			(effects
				(font
					(size 1.27 1.27)
					(thickness 0.15)
				)
				(justify left bottom)
				(hide yes)
			)
		)
		(pin "1"
		)
		(pin "2"
		)
		(instances
			(project "thunderbolt-gpu-adapter"
				(path ""
					(reference "C46")
					(unit 1)
				)
			)
		)
	)
	(symbol
		(lib_id "antmicroResistors0402:R_3k3_0402")
		(at 64.77 85.09 0)
		(unit 1)
		(exclude_from_sim no)
		(in_bom yes)
		(on_board yes)
		(dnp no)
		(property "Reference" "R15"
			(at 63.5 83.82 0)
			(effects
				(font
					(size 1.27 1.27)
					(thickness 0.15)
				)
			)
		)
		(property "Value" "R_3k3_0402"
			(at 85.09 97.79 0)
			(effects
				(font
					(size 1.27 1.27)
					(thickness 0.15)
				)
				(justify left bottom)
				(hide yes)
			)
		)
		(property "Footprint" "antmicro-footprints:R_0402_1005Metric"
			(at 85.09 100.33 0)
			(effects
				(font
					(size 1.27 1.27)
					(thickness 0.15)
				)
				(justify left bottom)
				(hide yes)
			)
		)
		(property "Datasheet" "https://www.bourns.com/docs/product-datasheets/cr.pdf"
			(at 85.09 102.87 0)
			(effects
				(font
					(size 1.27 1.27)
					(thickness 0.15)
				)
				(justify left bottom)
				(hide yes)
			)
		)
		(property "Description" ""
			(at 64.77 85.09 0)
			(effects
				(font
					(size 1.27 1.27)
				)
				(hide yes)
			)
		)
		(property "MPN" "CR0402-FX-3301GLF"
			(at 85.09 105.41 0)
			(effects
				(font
					(size 1.27 1.27)
					(thickness 0.15)
				)
				(justify left bottom)
				(hide yes)
			)
		)
		(property "Manufacturer" "Bourns"
			(at 85.09 107.95 0)
			(effects
				(font
					(size 1.27 1.27)
					(thickness 0.15)
				)
				(justify left bottom)
				(hide yes)
			)
		)
		(property "License" "Apache-2.0"
			(at 85.09 110.49 0)
			(effects
				(font
					(size 1.27 1.27)
					(thickness 0.15)
				)
				(justify left bottom)
				(hide yes)
			)
		)
		(property "Val" "3k3"
			(at 71.12 83.82 0)
			(effects
				(font
					(size 1.27 1.27)
					(thickness 0.15)
				)
			)
		)
		(property "Tolerance" "1%"
			(at 85.09 95.25 0)
			(effects
				(font
					(size 1.27 1.27)
				)
				(justify left bottom)
				(hide yes)
			)
		)
		(property "Author" "Antmicro"
			(at 85.09 113.03 0)
			(effects
				(font
					(size 1.27 1.27)
					(thickness 0.15)
				)
				(justify left bottom)
				(hide yes)
			)
		)
		(pin "1"
		)
		(pin "2"
		)
		(instances
			(project "thunderbolt-gpu-adapter"
				(path ""
					(reference "R15")
					(unit 1)
				)
			)
		)
	)
	(symbol
		(lib_id "antmicroCapacitorspol:C_Pol_330u_16V_KYOCERA-AVX-TCJ-E")
		(at 265.43 307.34 270)
		(unit 1)
		(exclude_from_sim no)
		(in_bom yes)
		(on_board yes)
		(dnp no)
		(fields_autoplaced yes)
		(property "Reference" "C144"
			(at 267.97 308.0766 90)
			(effects
				(font
					(size 1.27 1.27)
					(thickness 0.15)
				)
				(justify left)
			)
		)
		(property "Value" "C_Pol_330u_16V_KYOCERA-AVX-TCJ-E"
			(at 262.89 321.31 0)
			(effects
				(font
					(size 1.27 1.27)
					(thickness 0.15)
				)
				(justify left bottom)
				(hide yes)
			)
		)
		(property "Footprint" "antmicro-footprints:C_Pol_EIA-E"
			(at 257.81 321.31 0)
			(effects
				(font
					(size 1.27 1.27)
					(thickness 0.15)
				)
				(justify left bottom)
				(hide yes)
			)
		)
		(property "Datasheet" "https://spicat.kyocera-avx.com/product/tan/chartview/TCJE337M016R0070E/"
			(at 255.27 321.31 0)
			(effects
				(font
					(size 1.27 1.27)
					(thickness 0.15)
				)
				(justify left bottom)
				(hide yes)
			)
		)
		(property "Description" ""
			(at 265.43 307.34 0)
			(effects
				(font
					(size 1.27 1.27)
				)
				(hide yes)
			)
		)
		(property "Val" "330u"
			(at 267.97 310.6166 90)
			(effects
				(font
					(size 1.27 1.27)
					(thickness 0.15)
				)
				(justify left)
			)
		)
		(property "MPN" "TCJE337M016R0070E"
			(at 252.73 321.31 0)
			(effects
				(font
					(size 1.27 1.27)
					(thickness 0.15)
				)
				(justify left bottom)
				(hide yes)
			)
		)
		(property "Manufacturer" "KYOCERA AVX"
			(at 250.19 321.31 0)
			(effects
				(font
					(size 1.27 1.27)
					(thickness 0.15)
				)
				(justify left bottom)
				(hide yes)
			)
		)
		(property "License" "Apache-2.0"
			(at 247.65 321.31 0)
			(effects
				(font
					(size 1.27 1.27)
					(thickness 0.15)
				)
				(justify left bottom)
				(hide yes)
			)
		)
		(property "Author" "Antmicro"
			(at 245.11 321.31 0)
			(effects
				(font
					(size 1.27 1.27)
					(thickness 0.15)
				)
				(justify left bottom)
				(hide yes)
			)
		)
		(property "Voltage" "16V"
			(at 242.57 321.31 0)
			(effects
				(font
					(size 1.27 1.27)
				)
				(justify left bottom)
				(hide yes)
			)
		)
		(property "Dielectric" "template_dielectric"
			(at 240.03 321.31 0)
			(effects
				(font
					(size 1.27 1.27)
				)
				(justify left bottom)
				(hide yes)
			)
		)
		(pin "1"
		)
		(pin "2"
		)
		(instances
			(project "thunderbolt-gpu-adapter"
				(path ""
					(reference "C144")
					(unit 1)
				)
			)
		)
	)
	(symbol
		(lib_id "antmicroCapacitors0402:C_100n_0402")
		(at 91.44 392.43 90)
		(unit 1)
		(exclude_from_sim no)
		(in_bom yes)
		(on_board yes)
		(dnp no)
		(fields_autoplaced yes)
		(property "Reference" "C129"
			(at 93.98 388.6136 90)
			(effects
				(font
					(size 1.27 1.27)
					(thickness 0.15)
				)
				(justify right)
			)
		)
		(property "Value" "C_100n_0402"
			(at 101.6 372.11 0)
			(effects
				(font
					(size 1.27 1.27)
					(thickness 0.15)
				)
				(justify left bottom)
				(hide yes)
			)
		)
		(property "Footprint" "antmicro-footprints:C_0402_1005Metric"
			(at 104.14 372.11 0)
			(effects
				(font
					(size 1.27 1.27)
					(thickness 0.15)
				)
				(justify left bottom)
				(hide yes)
			)
		)
		(property "Datasheet" "https://www.murata.com/products/productdetail?partno=GRM155R61H104KE14%23"
			(at 106.68 372.11 0)
			(effects
				(font
					(size 1.27 1.27)
					(thickness 0.15)
				)
				(justify left bottom)
				(hide yes)
			)
		)
		(property "Description" ""
			(at 91.44 392.43 0)
			(effects
				(font
					(size 1.27 1.27)
				)
				(hide yes)
			)
		)
		(property "MPN" "GRM155R61H104KE14D"
			(at 109.22 372.11 0)
			(effects
				(font
					(size 1.27 1.27)
					(thickness 0.15)
				)
				(justify left bottom)
				(hide yes)
			)
		)
		(property "Manufacturer" "Murata"
			(at 111.76 372.11 0)
			(effects
				(font
					(size 1.27 1.27)
					(thickness 0.15)
				)
				(justify left bottom)
				(hide yes)
			)
		)
		(property "License" "Apache-2.0"
			(at 114.3 372.11 0)
			(effects
				(font
					(size 1.27 1.27)
					(thickness 0.15)
				)
				(justify left bottom)
				(hide yes)
			)
		)
		(property "Val" "100n"
			(at 93.98 391.1536 90)
			(effects
				(font
					(size 1.27 1.27)
					(thickness 0.15)
				)
				(justify right)
			)
		)
		(property "Voltage" "50V"
			(at 119.38 372.11 0)
			(effects
				(font
					(size 1.27 1.27)
				)
				(justify left bottom)
				(hide yes)
			)
		)
		(property "Dielectric" "X5R"
			(at 121.92 372.11 0)
			(effects
				(font
					(size 1.27 1.27)
				)
				(justify left bottom)
				(hide yes)
			)
		)
		(property "Author" "Antmicro"
			(at 116.84 372.11 0)
			(effects
				(font
					(size 1.27 1.27)
					(thickness 0.15)
				)
				(justify left bottom)
				(hide yes)
			)
		)
		(pin "1"
		)
		(pin "2"
		)
		(instances
			(project "thunderbolt-gpu-adapter"
				(path ""
					(reference "C129")
					(unit 1)
				)
			)
		)
	)
	(symbol
		(lib_id "antmicroCapacitors0402:C_33p_0402")
		(at 151.13 353.06 90)
		(unit 1)
		(exclude_from_sim no)
		(in_bom yes)
		(on_board yes)
		(dnp no)
		(fields_autoplaced yes)
		(property "Reference" "C33"
			(at 153.67 349.2436 90)
			(effects
				(font
					(size 1.27 1.27)
					(thickness 0.15)
				)
				(justify right)
			)
		)
		(property "Value" "C_33p_0402"
			(at 161.29 332.74 0)
			(effects
				(font
					(size 1.27 1.27)
					(thickness 0.15)
				)
				(justify left bottom)
				(hide yes)
			)
		)
		(property "Footprint" "antmicro-footprints:C_0402_1005Metric"
			(at 163.83 332.74 0)
			(effects
				(font
					(size 1.27 1.27)
					(thickness 0.15)
				)
				(justify left bottom)
				(hide yes)
			)
		)
		(property "Datasheet" "https://spicat.kyocera-avx.com/product/mlcc/chartview/04025A330FAT2A/"
			(at 166.37 332.74 0)
			(effects
				(font
					(size 1.27 1.27)
					(thickness 0.15)
				)
				(justify left bottom)
				(hide yes)
			)
		)
		(property "Description" ""
			(at 151.13 353.06 0)
			(effects
				(font
					(size 1.27 1.27)
				)
				(hide yes)
			)
		)
		(property "MPN" "04025A330FAT2A"
			(at 168.91 332.74 0)
			(effects
				(font
					(size 1.27 1.27)
					(thickness 0.15)
				)
				(justify left bottom)
				(hide yes)
			)
		)
		(property "Manufacturer" "KYOCERA AVX"
			(at 171.45 332.74 0)
			(effects
				(font
					(size 1.27 1.27)
					(thickness 0.15)
				)
				(justify left bottom)
				(hide yes)
			)
		)
		(property "License" "Apache-2.0"
			(at 173.99 332.74 0)
			(effects
				(font
					(size 1.27 1.27)
					(thickness 0.15)
				)
				(justify left bottom)
				(hide yes)
			)
		)
		(property "Val" "33p"
			(at 153.67 351.7836 90)
			(effects
				(font
					(size 1.27 1.27)
					(thickness 0.15)
				)
				(justify right)
			)
		)
		(property "Voltage" ""
			(at 179.07 332.74 0)
			(effects
				(font
					(size 1.27 1.27)
				)
				(justify left bottom)
				(hide yes)
			)
		)
		(property "Dielectric" ""
			(at 181.61 332.74 0)
			(effects
				(font
					(size 1.27 1.27)
				)
				(justify left bottom)
				(hide yes)
			)
		)
		(property "Author" "Antmicro"
			(at 176.53 332.74 0)
			(effects
				(font
					(size 1.27 1.27)
					(thickness 0.15)
				)
				(justify left bottom)
				(hide yes)
			)
		)
		(pin "1"
		)
		(pin "2"
		)
		(instances
			(project "thunderbolt-gpu-adapter"
				(path ""
					(reference "C33")
					(unit 1)
				)
			)
		)
	)
	(symbol
		(lib_id "antmicroCapacitorsmisc:C_22u_25V_0805")
		(at 182.88 55.88 90)
		(unit 1)
		(exclude_from_sim no)
		(in_bom yes)
		(on_board yes)
		(dnp no)
		(fields_autoplaced yes)
		(property "Reference" "C48"
			(at 185.42 50.7936 90)
			(effects
				(font
					(size 1.27 1.27)
					(thickness 0.15)
				)
				(justify right)
			)
		)
		(property "Value" "C_22u_25V_0805"
			(at 193.04 35.56 0)
			(effects
				(font
					(size 1.27 1.27)
					(thickness 0.15)
				)
				(justify left bottom)
				(hide yes)
			)
		)
		(property "Footprint" "antmicro-footprints:C_0805_2012Metric"
			(at 195.58 35.56 0)
			(effects
				(font
					(size 1.27 1.27)
					(thickness 0.15)
				)
				(justify left bottom)
				(hide yes)
			)
		)
		(property "Datasheet" "https://product.samsungsem.com/mlcc/CL21A226MAYNNN.do"
			(at 198.12 35.56 0)
			(effects
				(font
					(size 1.27 1.27)
					(thickness 0.15)
				)
				(justify left bottom)
				(hide yes)
			)
		)
		(property "Description" ""
			(at 182.88 55.88 0)
			(effects
				(font
					(size 1.27 1.27)
				)
				(hide yes)
			)
		)
		(property "MPN" "CL21A226MAYNNNE"
			(at 200.66 35.56 0)
			(effects
				(font
					(size 1.27 1.27)
					(thickness 0.15)
				)
				(justify left bottom)
				(hide yes)
			)
		)
		(property "Manufacturer" "Samsung Electro-Mechanics"
			(at 203.2 35.56 0)
			(effects
				(font
					(size 1.27 1.27)
					(thickness 0.15)
				)
				(justify left bottom)
				(hide yes)
			)
		)
		(property "License" "Apache-2.0"
			(at 205.74 35.56 0)
			(effects
				(font
					(size 1.27 1.27)
					(thickness 0.15)
				)
				(justify left bottom)
				(hide yes)
			)
		)
		(property "Val" "22u"
			(at 185.42 53.3336 90)
			(effects
				(font
					(size 1.27 1.27)
					(thickness 0.15)
				)
				(justify right)
			)
		)
		(property "Voltage" "25V"
			(at 185.42 55.8736 90)
			(effects
				(font
					(size 1.27 1.27)
				)
				(justify right)
			)
		)
		(property "Dielectric" "X5R"
			(at 213.36 35.56 0)
			(effects
				(font
					(size 1.27 1.27)
				)
				(justify left bottom)
				(hide yes)
			)
		)
		(property "Author" "Antmicro"
			(at 208.28 35.56 0)
			(effects
				(font
					(size 1.27 1.27)
					(thickness 0.15)
				)
				(justify left bottom)
				(hide yes)
			)
		)
		(pin "1"
		)
		(pin "2"
		)
		(instances
			(project "thunderbolt-gpu-adapter"
				(path ""
					(reference "C48")
					(unit 1)
				)
			)
		)
	)
	(symbol
		(lib_id "antmicroResistors0402:R_10k_0402")
		(at 64.77 110.49 0)
		(unit 1)
		(exclude_from_sim no)
		(in_bom yes)
		(on_board yes)
		(dnp no)
		(property "Reference" "R20"
			(at 67.31 112.395 0)
			(effects
				(font
					(size 1.27 1.27)
					(thickness 0.15)
				)
			)
		)
		(property "Value" "R_10k_0402"
			(at 85.09 123.19 0)
			(effects
				(font
					(size 1.27 1.27)
					(thickness 0.15)
				)
				(justify left bottom)
				(hide yes)
			)
		)
		(property "Footprint" "antmicro-footprints:R_0402_1005Metric"
			(at 85.09 125.73 0)
			(effects
				(font
					(size 1.27 1.27)
					(thickness 0.15)
				)
				(justify left bottom)
				(hide yes)
			)
		)
		(property "Datasheet" "https://www.bourns.com/docs/product-datasheets/cr.pdf"
			(at 85.09 128.27 0)
			(effects
				(font
					(size 1.27 1.27)
					(thickness 0.15)
				)
				(justify left bottom)
				(hide yes)
			)
		)
		(property "Description" ""
			(at 64.77 110.49 0)
			(effects
				(font
					(size 1.27 1.27)
				)
				(hide yes)
			)
		)
		(property "MPN" "CR0402-FX-1002GLF"
			(at 85.09 130.81 0)
			(effects
				(font
					(size 1.27 1.27)
					(thickness 0.15)
				)
				(justify left bottom)
				(hide yes)
			)
		)
		(property "Manufacturer" "Bourns"
			(at 85.09 133.35 0)
			(effects
				(font
					(size 1.27 1.27)
					(thickness 0.15)
				)
				(justify left bottom)
				(hide yes)
			)
		)
		(property "License" "Apache-2.0"
			(at 85.09 135.89 0)
			(effects
				(font
					(size 1.27 1.27)
					(thickness 0.15)
				)
				(justify left bottom)
				(hide yes)
			)
		)
		(property "Val" "10k"
			(at 67.31 110.49 0)
			(effects
				(font
					(size 1.27 1.27)
					(thickness 0.15)
				)
			)
		)
		(property "Tolerance" "1%"
			(at 85.09 120.65 0)
			(effects
				(font
					(size 1.27 1.27)
				)
				(justify left bottom)
				(hide yes)
			)
		)
		(property "Author" "Antmicro"
			(at 85.09 138.43 0)
			(effects
				(font
					(size 1.27 1.27)
					(thickness 0.15)
				)
				(justify left bottom)
				(hide yes)
			)
		)
		(pin "1"
		)
		(pin "2"
		)
		(instances
			(project "thunderbolt-gpu-adapter"
				(path ""
					(reference "R20")
					(unit 1)
				)
			)
		)
	)
	(symbol
		(lib_id "antmicroResistors0402:R_100k_0402")
		(at 50.8 165.1 90)
		(unit 1)
		(exclude_from_sim no)
		(in_bom yes)
		(on_board yes)
		(dnp no)
		(fields_autoplaced yes)
		(property "Reference" "R10"
			(at 53.34 161.29 90)
			(effects
				(font
					(size 1.27 1.27)
					(thickness 0.15)
				)
				(justify right)
			)
		)
		(property "Value" "R_100k_0402"
			(at 63.5 144.78 0)
			(effects
				(font
					(size 1.27 1.27)
					(thickness 0.15)
				)
				(justify left bottom)
				(hide yes)
			)
		)
		(property "Footprint" "antmicro-footprints:R_0402_1005Metric"
			(at 66.04 144.78 0)
			(effects
				(font
					(size 1.27 1.27)
					(thickness 0.15)
				)
				(justify left bottom)
				(hide yes)
			)
		)
		(property "Datasheet" "https://www.bourns.com/docs/product-datasheets/cr.pdf"
			(at 68.58 144.78 0)
			(effects
				(font
					(size 1.27 1.27)
					(thickness 0.15)
				)
				(justify left bottom)
				(hide yes)
			)
		)
		(property "Description" ""
			(at 50.8 165.1 0)
			(effects
				(font
					(size 1.27 1.27)
				)
				(hide yes)
			)
		)
		(property "MPN" "CR0402-FX-1003GLF"
			(at 71.12 144.78 0)
			(effects
				(font
					(size 1.27 1.27)
					(thickness 0.15)
				)
				(justify left bottom)
				(hide yes)
			)
		)
		(property "Manufacturer" "Bourns"
			(at 73.66 144.78 0)
			(effects
				(font
					(size 1.27 1.27)
					(thickness 0.15)
				)
				(justify left bottom)
				(hide yes)
			)
		)
		(property "License" "Apache-2.0"
			(at 76.2 144.78 0)
			(effects
				(font
					(size 1.27 1.27)
					(thickness 0.15)
				)
				(justify left bottom)
				(hide yes)
			)
		)
		(property "Val" "100k"
			(at 53.34 163.83 90)
			(effects
				(font
					(size 1.27 1.27)
					(thickness 0.15)
				)
				(justify right)
			)
		)
		(property "Tolerance" "1%"
			(at 60.96 144.78 0)
			(effects
				(font
					(size 1.27 1.27)
				)
				(justify left bottom)
				(hide yes)
			)
		)
		(property "Author" "Antmicro"
			(at 78.74 144.78 0)
			(effects
				(font
					(size 1.27 1.27)
					(thickness 0.15)
				)
				(justify left bottom)
				(hide yes)
			)
		)
		(pin "1"
		)
		(pin "2"
		)
		(instances
			(project "thunderbolt-gpu-adapter"
				(path ""
					(reference "R10")
					(unit 1)
				)
			)
		)
	)
	(symbol
		(lib_id "antmicropower:GND")
		(at 43.18 113.03 0)
		(unit 1)
		(exclude_from_sim no)
		(in_bom yes)
		(on_board yes)
		(dnp no)
		(property "Reference" "#PWR021"
			(at 43.18 119.38 0)
			(effects
				(font
					(size 1.27 1.27)
				)
				(hide yes)
			)
		)
		(property "Value" "GND"
			(at 43.18 116.84 0)
			(effects
				(font
					(size 1.27 1.27)
				)
			)
		)
		(property "Footprint" ""
			(at 43.18 113.03 0)
			(effects
				(font
					(size 1.27 1.27)
				)
				(hide yes)
			)
		)
		(property "Datasheet" ""
			(at 43.18 113.03 0)
			(effects
				(font
					(size 1.27 1.27)
				)
				(hide yes)
			)
		)
		(property "Description" ""
			(at 43.18 113.03 0)
			(effects
				(font
					(size 1.27 1.27)
				)
				(hide yes)
			)
		)
		(property "Author" "Antmicro"
			(at 52.07 120.65 0)
			(effects
				(font
					(size 1.27 1.27)
					(thickness 0.15)
				)
				(justify left bottom)
				(hide yes)
			)
		)
		(property "License" "Apache-2.0"
			(at 52.07 123.19 0)
			(effects
				(font
					(size 1.27 1.27)
					(thickness 0.15)
				)
				(justify left bottom)
				(hide yes)
			)
		)
		(pin "1"
		)
		(instances
			(project "thunderbolt-gpu-adapter"
				(path ""
					(reference "#PWR021")
					(unit 1)
				)
			)
		)
	)
	(symbol
		(lib_id "antmicroResistors0402:R_110k_0402")
		(at 233.68 217.17 90)
		(unit 1)
		(exclude_from_sim no)
		(in_bom yes)
		(on_board yes)
		(dnp no)
		(fields_autoplaced yes)
		(property "Reference" "R43"
			(at 231.14 213.36 90)
			(effects
				(font
					(size 1.27 1.27)
					(thickness 0.15)
				)
				(justify left)
			)
		)
		(property "Value" "R_110k_0402"
			(at 246.38 196.85 0)
			(effects
				(font
					(size 1.27 1.27)
					(thickness 0.15)
				)
				(justify left bottom)
				(hide yes)
			)
		)
		(property "Footprint" "antmicro-footprints:R_0402_1005Metric"
			(at 248.92 196.85 0)
			(effects
				(font
					(size 1.27 1.27)
					(thickness 0.15)
				)
				(justify left bottom)
				(hide yes)
			)
		)
		(property "Datasheet" "https://www.bourns.com/docs/product-datasheets/cr.pdf"
			(at 251.46 196.85 0)
			(effects
				(font
					(size 1.27 1.27)
					(thickness 0.15)
				)
				(justify left bottom)
				(hide yes)
			)
		)
		(property "Description" ""
			(at 233.68 217.17 0)
			(effects
				(font
					(size 1.27 1.27)
				)
				(hide yes)
			)
		)
		(property "MPN" "CR0402-FX-1103GLF"
			(at 254 196.85 0)
			(effects
				(font
					(size 1.27 1.27)
					(thickness 0.15)
				)
				(justify left bottom)
				(hide yes)
			)
		)
		(property "Manufacturer" "Bourns"
			(at 256.54 196.85 0)
			(effects
				(font
					(size 1.27 1.27)
					(thickness 0.15)
				)
				(justify left bottom)
				(hide yes)
			)
		)
		(property "License" "Apache-2.0"
			(at 259.08 196.85 0)
			(effects
				(font
					(size 1.27 1.27)
					(thickness 0.15)
				)
				(justify left bottom)
				(hide yes)
			)
		)
		(property "Val" "110k"
			(at 231.14 215.9 90)
			(effects
				(font
					(size 1.27 1.27)
					(thickness 0.15)
				)
				(justify left)
			)
		)
		(property "Tolerance" "1%"
			(at 243.84 196.85 0)
			(effects
				(font
					(size 1.27 1.27)
				)
				(justify left bottom)
				(hide yes)
			)
		)
		(property "Author" "Antmicro"
			(at 261.62 196.85 0)
			(effects
				(font
					(size 1.27 1.27)
					(thickness 0.15)
				)
				(justify left bottom)
				(hide yes)
			)
		)
		(pin "1"
		)
		(pin "2"
		)
		(instances
			(project "thunderbolt-gpu-adapter"
				(path ""
					(reference "R43")
					(unit 1)
				)
			)
		)
	)
	(symbol
		(lib_id "antmicropower:GND")
		(at 217.17 137.16 0)
		(unit 1)
		(exclude_from_sim no)
		(in_bom yes)
		(on_board yes)
		(dnp no)
		(property "Reference" "#PWR0202"
			(at 217.17 143.51 0)
			(effects
				(font
					(size 1.27 1.27)
				)
				(hide yes)
			)
		)
		(property "Value" "GND"
			(at 217.17 140.97 0)
			(effects
				(font
					(size 1.27 1.27)
				)
			)
		)
		(property "Footprint" ""
			(at 217.17 137.16 0)
			(effects
				(font
					(size 1.27 1.27)
				)
				(hide yes)
			)
		)
		(property "Datasheet" ""
			(at 217.17 137.16 0)
			(effects
				(font
					(size 1.27 1.27)
				)
				(hide yes)
			)
		)
		(property "Description" ""
			(at 217.17 137.16 0)
			(effects
				(font
					(size 1.27 1.27)
				)
				(hide yes)
			)
		)
		(property "Author" "Antmicro"
			(at 226.06 144.78 0)
			(effects
				(font
					(size 1.27 1.27)
					(thickness 0.15)
				)
				(justify left bottom)
				(hide yes)
			)
		)
		(property "License" "Apache-2.0"
			(at 226.06 147.32 0)
			(effects
				(font
					(size 1.27 1.27)
					(thickness 0.15)
				)
				(justify left bottom)
				(hide yes)
			)
		)
		(pin "1"
		)
		(instances
			(project "thunderbolt-gpu-adapter"
				(path ""
					(reference "#PWR0202")
					(unit 1)
				)
			)
		)
	)
	(symbol
		(lib_id "antmicropower:GND")
		(at 29.21 207.01 0)
		(unit 1)
		(exclude_from_sim no)
		(in_bom yes)
		(on_board yes)
		(dnp no)
		(property "Reference" "#PWR02"
			(at 29.21 213.36 0)
			(effects
				(font
					(size 1.27 1.27)
				)
				(hide yes)
			)
		)
		(property "Value" "GND"
			(at 27.305 211.455 0)
			(effects
				(font
					(size 1.27 1.27)
					(thickness 0.15)
				)
				(justify left bottom)
			)
		)
		(property "Footprint" ""
			(at 29.21 207.01 0)
			(effects
				(font
					(size 1.27 1.27)
					(thickness 0.15)
				)
				(justify left bottom)
				(hide yes)
			)
		)
		(property "Datasheet" ""
			(at 29.21 207.01 0)
			(effects
				(font
					(size 1.27 1.27)
					(thickness 0.15)
				)
				(justify left bottom)
				(hide yes)
			)
		)
		(property "Description" ""
			(at 29.21 207.01 0)
			(effects
				(font
					(size 1.27 1.27)
				)
				(hide yes)
			)
		)
		(property "Author" "Antmicro"
			(at 38.1 214.63 0)
			(effects
				(font
					(size 1.27 1.27)
					(thickness 0.15)
				)
				(justify left bottom)
				(hide yes)
			)
		)
		(property "License" "Apache-2.0"
			(at 38.1 217.17 0)
			(effects
				(font
					(size 1.27 1.27)
					(thickness 0.15)
				)
				(justify left bottom)
				(hide yes)
			)
		)
		(pin "1"
		)
		(instances
			(project "thunderbolt-gpu-adapter"
				(path ""
					(reference "#PWR02")
					(unit 1)
				)
			)
		)
	)
	(symbol
		(lib_id "antmicroCapacitors0402:C_4u7_25V_0402")
		(at 64.77 52.07 0)
		(unit 1)
		(exclude_from_sim no)
		(in_bom yes)
		(on_board yes)
		(dnp no)
		(fields_autoplaced yes)
		(property "Reference" "C21"
			(at 64.77 50.8 0)
			(effects
				(font
					(size 1.27 1.27)
					(thickness 0.15)
				)
			)
		)
		(property "Value" "C_4u7_25V_0402"
			(at 85.09 62.23 0)
			(effects
				(font
					(size 1.27 1.27)
					(thickness 0.15)
				)
				(justify left bottom)
				(hide yes)
			)
		)
		(property "Footprint" "antmicro-footprints:C_0402_1005Metric"
			(at 85.09 64.77 0)
			(effects
				(font
					(size 1.27 1.27)
					(thickness 0.15)
				)
				(justify left bottom)
				(hide yes)
			)
		)
		(property "Datasheet" "https://www.murata.com/products/productdetail?partno=GRM155C61E475ME15%23"
			(at 85.09 67.31 0)
			(effects
				(font
					(size 1.27 1.27)
					(thickness 0.15)
				)
				(justify left bottom)
				(hide yes)
			)
		)
		(property "Description" ""
			(at 64.77 52.07 0)
			(effects
				(font
					(size 1.27 1.27)
				)
				(hide yes)
			)
		)
		(property "MPN" "GRM155C61E475ME15J"
			(at 85.09 69.85 0)
			(effects
				(font
					(size 1.27 1.27)
					(thickness 0.15)
				)
				(justify left bottom)
				(hide yes)
			)
		)
		(property "Manufacturer" "Murata"
			(at 85.09 72.39 0)
			(effects
				(font
					(size 1.27 1.27)
					(thickness 0.15)
				)
				(justify left bottom)
				(hide yes)
			)
		)
		(property "License" "Apache-2.0"
			(at 85.09 74.93 0)
			(effects
				(font
					(size 1.27 1.27)
					(thickness 0.15)
				)
				(justify left bottom)
				(hide yes)
			)
		)
		(property "Val" "4u7"
			(at 69.85 50.8 0)
			(effects
				(font
					(size 1.27 1.27)
					(thickness 0.15)
				)
			)
		)
		(property "Voltage" "25V"
			(at 68.58 52.07 0)
			(effects
				(font
					(size 1.27 1.27)
				)
				(justify left bottom)
				(hide yes)
			)
		)
		(property "Dielectric" "X5S"
			(at 85.09 82.55 0)
			(effects
				(font
					(size 1.27 1.27)
				)
				(justify left bottom)
				(hide yes)
			)
		)
		(property "Author" "Antmicro"
			(at 85.09 77.47 0)
			(effects
				(font
					(size 1.27 1.27)
					(thickness 0.15)
				)
				(justify left bottom)
				(hide yes)
			)
		)
		(pin "1"
		)
		(pin "2"
		)
		(instances
			(project "thunderbolt-gpu-adapter"
				(path ""
					(reference "C21")
					(unit 1)
				)
			)
		)
	)
	(symbol
		(lib_id "antmicroResistors0402:R_10k_0402")
		(at 233.68 224.79 90)
		(unit 1)
		(exclude_from_sim no)
		(in_bom yes)
		(on_board yes)
		(dnp no)
		(fields_autoplaced yes)
		(property "Reference" "R44"
			(at 231.14 220.98 90)
			(effects
				(font
					(size 1.27 1.27)
					(thickness 0.15)
				)
				(justify left)
			)
		)
		(property "Value" "R_10k_0402"
			(at 246.38 204.47 0)
			(effects
				(font
					(size 1.27 1.27)
					(thickness 0.15)
				)
				(justify left bottom)
				(hide yes)
			)
		)
		(property "Footprint" "antmicro-footprints:R_0402_1005Metric"
			(at 248.92 204.47 0)
			(effects
				(font
					(size 1.27 1.27)
					(thickness 0.15)
				)
				(justify left bottom)
				(hide yes)
			)
		)
		(property "Datasheet" "https://www.bourns.com/docs/product-datasheets/cr.pdf"
			(at 251.46 204.47 0)
			(effects
				(font
					(size 1.27 1.27)
					(thickness 0.15)
				)
				(justify left bottom)
				(hide yes)
			)
		)
		(property "Description" ""
			(at 233.68 224.79 0)
			(effects
				(font
					(size 1.27 1.27)
				)
				(hide yes)
			)
		)
		(property "MPN" "CR0402-FX-1002GLF"
			(at 254 204.47 0)
			(effects
				(font
					(size 1.27 1.27)
					(thickness 0.15)
				)
				(justify left bottom)
				(hide yes)
			)
		)
		(property "Manufacturer" "Bourns"
			(at 256.54 204.47 0)
			(effects
				(font
					(size 1.27 1.27)
					(thickness 0.15)
				)
				(justify left bottom)
				(hide yes)
			)
		)
		(property "License" "Apache-2.0"
			(at 259.08 204.47 0)
			(effects
				(font
					(size 1.27 1.27)
					(thickness 0.15)
				)
				(justify left bottom)
				(hide yes)
			)
		)
		(property "Val" "10k"
			(at 231.14 223.52 90)
			(effects
				(font
					(size 1.27 1.27)
					(thickness 0.15)
				)
				(justify left)
			)
		)
		(property "Tolerance" "1%"
			(at 243.84 204.47 0)
			(effects
				(font
					(size 1.27 1.27)
				)
				(justify left bottom)
				(hide yes)
			)
		)
		(property "Author" "Antmicro"
			(at 261.62 204.47 0)
			(effects
				(font
					(size 1.27 1.27)
					(thickness 0.15)
				)
				(justify left bottom)
				(hide yes)
			)
		)
		(pin "1"
		)
		(pin "2"
		)
		(instances
			(project "thunderbolt-gpu-adapter"
				(path ""
					(reference "R44")
					(unit 1)
				)
			)
		)
	)
	(symbol
		(lib_id "antmicroFerriteBeadsandChips:FB_30Z_8.5A_Murata-BLM21SN_0805")
		(at 35.56 198.12 0)
		(unit 1)
		(exclude_from_sim no)
		(in_bom yes)
		(on_board yes)
		(dnp no)
		(fields_autoplaced yes)
		(property "Reference" "FB1"
			(at 38.0619 191.77 0)
			(effects
				(font
					(size 1.27 1.27)
					(thickness 0.15)
				)
			)
		)
		(property "Value" "FB_30Z_8.5A_Murata-BLM21SN_0805"
			(at 49.53 200.66 0)
			(effects
				(font
					(size 1.27 1.27)
					(thickness 0.15)
				)
				(justify left bottom)
				(hide yes)
			)
		)
		(property "Footprint" "antmicro-footprints:FB_0805_2012Metric"
			(at 49.53 205.74 0)
			(effects
				(font
					(size 1.27 1.27)
					(thickness 0.15)
				)
				(justify left bottom)
				(hide yes)
			)
		)
		(property "Datasheet" "https://www.murata.com/en-sg/products/productdata/8796738977822/ENFA0005.pdf?1519270210000"
			(at 49.53 208.28 0)
			(effects
				(font
					(size 1.27 1.27)
					(thickness 0.15)
				)
				(justify left bottom)
				(hide yes)
			)
		)
		(property "Description" ""
			(at 35.56 198.12 0)
			(effects
				(font
					(size 1.27 1.27)
				)
				(hide yes)
			)
		)
		(property "MPN" "BLM21SN300SZ1D"
			(at 49.53 210.82 0)
			(effects
				(font
					(size 1.27 1.27)
					(thickness 0.15)
				)
				(justify left bottom)
				(hide yes)
			)
		)
		(property "Manufacturer" "Murata"
			(at 49.53 213.36 0)
			(effects
				(font
					(size 1.27 1.27)
					(thickness 0.15)
				)
				(justify left bottom)
				(hide yes)
			)
		)
		(property "License" "Apache-2.0"
			(at 49.53 218.44 0)
			(effects
				(font
					(size 1.27 1.27)
					(thickness 0.15)
				)
				(justify left bottom)
				(hide yes)
			)
		)
		(property "Author" "Antmicro"
			(at 49.53 215.9 0)
			(effects
				(font
					(size 1.27 1.27)
					(thickness 0.15)
				)
				(justify left bottom)
				(hide yes)
			)
		)
		(property "Val" "30Z/8.5A"
			(at 38.0619 194.31 0)
			(effects
				(font
					(size 1.27 1.27)
				)
			)
		)
		(property "Current" ""
			(at 55.88 220.98 0)
			(effects
				(font
					(size 1.27 1.27)
					(thickness 0.15)
				)
				(justify left bottom)
				(hide yes)
			)
		)
		(pin "1"
		)
		(pin "2"
		)
		(instances
			(project "thunderbolt-gpu-adapter"
				(path ""
					(reference "FB1")
					(unit 1)
				)
			)
		)
	)
	(symbol
		(lib_id "antmicropower:GND")
		(at 255.27 128.27 0)
		(unit 1)
		(exclude_from_sim no)
		(in_bom yes)
		(on_board yes)
		(dnp no)
		(property "Reference" "#PWR0200"
			(at 255.27 134.62 0)
			(effects
				(font
					(size 1.27 1.27)
				)
				(hide yes)
			)
		)
		(property "Value" "GND"
			(at 255.27 132.08 0)
			(effects
				(font
					(size 1.27 1.27)
				)
			)
		)
		(property "Footprint" ""
			(at 255.27 128.27 0)
			(effects
				(font
					(size 1.27 1.27)
				)
				(hide yes)
			)
		)
		(property "Datasheet" ""
			(at 255.27 128.27 0)
			(effects
				(font
					(size 1.27 1.27)
				)
				(hide yes)
			)
		)
		(property "Description" ""
			(at 255.27 128.27 0)
			(effects
				(font
					(size 1.27 1.27)
				)
				(hide yes)
			)
		)
		(property "Author" "Antmicro"
			(at 264.16 135.89 0)
			(effects
				(font
					(size 1.27 1.27)
					(thickness 0.15)
				)
				(justify left bottom)
				(hide yes)
			)
		)
		(property "License" "Apache-2.0"
			(at 264.16 138.43 0)
			(effects
				(font
					(size 1.27 1.27)
					(thickness 0.15)
				)
				(justify left bottom)
				(hide yes)
			)
		)
		(pin "1"
		)
		(instances
			(project "thunderbolt-gpu-adapter"
				(path ""
					(reference "#PWR0200")
					(unit 1)
				)
			)
		)
	)
	(symbol
		(lib_id "antmicroTestPoints:TP_1mm_SMD")
		(at 190.5 345.44 90)
		(unit 1)
		(exclude_from_sim no)
		(in_bom no)
		(on_board yes)
		(dnp no)
		(property "Reference" "TP7"
			(at 188.595 340.36 90)
			(effects
				(font
					(size 1.27 1.27)
					(thickness 0.15)
				)
				(justify right)
			)
		)
		(property "Value" "TP_1mm_SMD"
			(at 192.405 342.2649 90)
			(effects
				(font
					(size 1.27 1.27)
					(thickness 0.15)
				)
				(justify right)
				(hide yes)
			)
		)
		(property "Footprint" "antmicro-footprints:TP_SMD_1mm"
			(at 200.66 330.2 0)
			(effects
				(font
					(size 1.27 1.27)
					(thickness 0.15)
				)
				(justify left bottom)
				(hide yes)
			)
		)
		(property "Datasheet" ""
			(at 203.2 330.2 0)
			(effects
				(font
					(size 1.27 1.27)
					(thickness 0.15)
				)
				(justify left bottom)
				(hide yes)
			)
		)
		(property "Description" ""
			(at 190.5 345.44 0)
			(effects
				(font
					(size 1.27 1.27)
				)
				(hide yes)
			)
		)
		(property "License" "Apache-2.0"
			(at 208.28 330.2 0)
			(effects
				(font
					(size 1.27 1.27)
					(thickness 0.15)
				)
				(justify left bottom)
				(hide yes)
			)
		)
		(property "Manufacturer" ""
			(at 192.405 344.8049 90)
			(effects
				(font
					(size 1.27 1.27)
				)
				(justify right)
				(hide yes)
			)
		)
		(property "MPN" ""
			(at 190.5 345.44 0)
			(effects
				(font
					(size 1.27 1.27)
				)
				(hide yes)
			)
		)
		(property "Author" "Antmicro"
			(at 205.74 330.2 0)
			(effects
				(font
					(size 1.27 1.27)
					(thickness 0.15)
				)
				(justify left bottom)
				(hide yes)
			)
		)
		(pin "1"
		)
		(instances
			(project "thunderbolt-gpu-adapter"
				(path ""
					(reference "TP7")
					(unit 1)
				)
			)
		)
	)
	(symbol
		(lib_id "antmicroCapacitors0603:C_22u_16V_0603")
		(at 46.99 266.7 90)
		(unit 1)
		(exclude_from_sim no)
		(in_bom yes)
		(on_board yes)
		(dnp no)
		(fields_autoplaced yes)
		(property "Reference" "C119"
			(at 49.53 262.8836 90)
			(effects
				(font
					(size 1.27 1.27)
					(thickness 0.15)
				)
				(justify right)
			)
		)
		(property "Value" "C_22u_16V_0603"
			(at 57.15 246.38 0)
			(effects
				(font
					(size 1.27 1.27)
					(thickness 0.15)
				)
				(justify left bottom)
				(hide yes)
			)
		)
		(property "Footprint" "antmicro-footprints:C_0603_1608Metric"
			(at 59.69 246.38 0)
			(effects
				(font
					(size 1.27 1.27)
					(thickness 0.15)
				)
				(justify left bottom)
				(hide yes)
			)
		)
		(property "Datasheet" "https://product.samsungsem.com/mlcc/CL10A226MO7JZN.do"
			(at 62.23 246.38 0)
			(effects
				(font
					(size 1.27 1.27)
					(thickness 0.15)
				)
				(justify left bottom)
				(hide yes)
			)
		)
		(property "Description" ""
			(at 46.99 266.7 0)
			(effects
				(font
					(size 1.27 1.27)
				)
				(hide yes)
			)
		)
		(property "MPN" "CL10A226MO7JZNC"
			(at 64.77 246.38 0)
			(effects
				(font
					(size 1.27 1.27)
					(thickness 0.15)
				)
				(justify left bottom)
				(hide yes)
			)
		)
		(property "Manufacturer" "Samsung Electro-Mechanics"
			(at 67.31 246.38 0)
			(effects
				(font
					(size 1.27 1.27)
					(thickness 0.15)
				)
				(justify left bottom)
				(hide yes)
			)
		)
		(property "License" "Apache-2.0"
			(at 69.85 246.38 0)
			(effects
				(font
					(size 1.27 1.27)
					(thickness 0.15)
				)
				(justify left bottom)
				(hide yes)
			)
		)
		(property "Val" "22u"
			(at 49.53 265.4236 90)
			(effects
				(font
					(size 1.27 1.27)
					(thickness 0.15)
				)
				(justify right)
			)
		)
		(property "Voltage" "16V"
			(at 74.93 246.38 0)
			(effects
				(font
					(size 1.27 1.27)
				)
				(justify left bottom)
				(hide yes)
			)
		)
		(property "Dielectric" ""
			(at 77.47 246.38 0)
			(effects
				(font
					(size 1.27 1.27)
				)
				(justify left bottom)
				(hide yes)
			)
		)
		(property "Author" "Antmicro"
			(at 72.39 246.38 0)
			(effects
				(font
					(size 1.27 1.27)
					(thickness 0.15)
				)
				(justify left bottom)
				(hide yes)
			)
		)
		(pin "1"
		)
		(pin "2"
		)
		(instances
			(project "thunderbolt-gpu-adapter"
				(path ""
					(reference "C119")
					(unit 1)
				)
			)
		)
	)
	(symbol
		(lib_id "antmicropower:GND")
		(at 172.72 364.49 0)
		(unit 1)
		(exclude_from_sim no)
		(in_bom yes)
		(on_board yes)
		(dnp no)
		(fields_autoplaced yes)
		(property "Reference" "#PWR061"
			(at 172.72 370.84 0)
			(effects
				(font
					(size 1.27 1.27)
				)
				(hide yes)
			)
		)
		(property "Value" "GND"
			(at 172.72 368.3 0)
			(effects
				(font
					(size 1.27 1.27)
				)
			)
		)
		(property "Footprint" ""
			(at 172.72 364.49 0)
			(effects
				(font
					(size 1.27 1.27)
				)
				(hide yes)
			)
		)
		(property "Datasheet" ""
			(at 172.72 364.49 0)
			(effects
				(font
					(size 1.27 1.27)
				)
				(hide yes)
			)
		)
		(property "Description" ""
			(at 172.72 364.49 0)
			(effects
				(font
					(size 1.27 1.27)
				)
				(hide yes)
			)
		)
		(property "Author" "Antmicro"
			(at 181.61 372.11 0)
			(effects
				(font
					(size 1.27 1.27)
					(thickness 0.15)
				)
				(justify left bottom)
				(hide yes)
			)
		)
		(property "License" "Apache-2.0"
			(at 181.61 374.65 0)
			(effects
				(font
					(size 1.27 1.27)
					(thickness 0.15)
				)
				(justify left bottom)
				(hide yes)
			)
		)
		(pin "1"
		)
		(instances
			(project "thunderbolt-gpu-adapter"
				(path ""
					(reference "#PWR061")
					(unit 1)
				)
			)
		)
	)
	(symbol
		(lib_id "antmicroResistors0402:R_10k_0402")
		(at 27.94 68.58 90)
		(unit 1)
		(exclude_from_sim no)
		(in_bom yes)
		(on_board yes)
		(dnp no)
		(property "Reference" "R2"
			(at 29.21 64.77 90)
			(effects
				(font
					(size 1.27 1.27)
					(thickness 0.15)
				)
				(justify right)
			)
		)
		(property "Value" "R_10k_0402"
			(at 40.64 48.26 0)
			(effects
				(font
					(size 1.27 1.27)
					(thickness 0.15)
				)
				(justify left bottom)
				(hide yes)
			)
		)
		(property "Footprint" "antmicro-footprints:R_0402_1005Metric"
			(at 43.18 48.26 0)
			(effects
				(font
					(size 1.27 1.27)
					(thickness 0.15)
				)
				(justify left bottom)
				(hide yes)
			)
		)
		(property "Datasheet" "https://www.bourns.com/docs/product-datasheets/cr.pdf"
			(at 45.72 48.26 0)
			(effects
				(font
					(size 1.27 1.27)
					(thickness 0.15)
				)
				(justify left bottom)
				(hide yes)
			)
		)
		(property "Description" ""
			(at 27.94 68.58 0)
			(effects
				(font
					(size 1.27 1.27)
				)
				(hide yes)
			)
		)
		(property "MPN" "CR0402-FX-1002GLF"
			(at 48.26 48.26 0)
			(effects
				(font
					(size 1.27 1.27)
					(thickness 0.15)
				)
				(justify left bottom)
				(hide yes)
			)
		)
		(property "Manufacturer" "Bourns"
			(at 50.8 48.26 0)
			(effects
				(font
					(size 1.27 1.27)
					(thickness 0.15)
				)
				(justify left bottom)
				(hide yes)
			)
		)
		(property "License" "Apache-2.0"
			(at 53.34 48.26 0)
			(effects
				(font
					(size 1.27 1.27)
					(thickness 0.15)
				)
				(justify left bottom)
				(hide yes)
			)
		)
		(property "Val" "10k"
			(at 29.21 67.31 90)
			(effects
				(font
					(size 1.27 1.27)
					(thickness 0.15)
				)
				(justify right)
			)
		)
		(property "Tolerance" "1%"
			(at 38.1 48.26 0)
			(effects
				(font
					(size 1.27 1.27)
				)
				(justify left bottom)
				(hide yes)
			)
		)
		(property "Author" "Antmicro"
			(at 55.88 48.26 0)
			(effects
				(font
					(size 1.27 1.27)
					(thickness 0.15)
				)
				(justify left bottom)
				(hide yes)
			)
		)
		(pin "1"
		)
		(pin "2"
		)
		(instances
			(project "thunderbolt-gpu-adapter"
				(path ""
					(reference "R2")
					(unit 1)
				)
			)
		)
	)
	(symbol
		(lib_id "antmicropower:GND")
		(at 46.99 67.31 0)
		(unit 1)
		(exclude_from_sim no)
		(in_bom yes)
		(on_board yes)
		(dnp no)
		(property "Reference" "#PWR0222"
			(at 46.99 73.66 0)
			(effects
				(font
					(size 1.27 1.27)
				)
				(hide yes)
			)
		)
		(property "Value" "GND"
			(at 46.99 71.12 0)
			(effects
				(font
					(size 1.27 1.27)
				)
			)
		)
		(property "Footprint" ""
			(at 46.99 67.31 0)
			(effects
				(font
					(size 1.27 1.27)
				)
				(hide yes)
			)
		)
		(property "Datasheet" ""
			(at 46.99 67.31 0)
			(effects
				(font
					(size 1.27 1.27)
				)
				(hide yes)
			)
		)
		(property "Description" ""
			(at 46.99 67.31 0)
			(effects
				(font
					(size 1.27 1.27)
				)
				(hide yes)
			)
		)
		(property "Author" "Antmicro"
			(at 55.88 74.93 0)
			(effects
				(font
					(size 1.27 1.27)
					(thickness 0.15)
				)
				(justify left bottom)
				(hide yes)
			)
		)
		(property "License" "Apache-2.0"
			(at 55.88 77.47 0)
			(effects
				(font
					(size 1.27 1.27)
					(thickness 0.15)
				)
				(justify left bottom)
				(hide yes)
			)
		)
		(pin "1"
		)
		(instances
			(project "thunderbolt-gpu-adapter"
				(path ""
					(reference "#PWR0222")
					(unit 1)
				)
			)
		)
	)
	(symbol
		(lib_id "antmicropower:GND")
		(at 160.02 364.49 0)
		(unit 1)
		(exclude_from_sim no)
		(in_bom yes)
		(on_board yes)
		(dnp no)
		(fields_autoplaced yes)
		(property "Reference" "#PWR054"
			(at 160.02 370.84 0)
			(effects
				(font
					(size 1.27 1.27)
				)
				(hide yes)
			)
		)
		(property "Value" "GND"
			(at 160.02 368.3 0)
			(effects
				(font
					(size 1.27 1.27)
				)
			)
		)
		(property "Footprint" ""
			(at 160.02 364.49 0)
			(effects
				(font
					(size 1.27 1.27)
				)
				(hide yes)
			)
		)
		(property "Datasheet" ""
			(at 160.02 364.49 0)
			(effects
				(font
					(size 1.27 1.27)
				)
				(hide yes)
			)
		)
		(property "Description" ""
			(at 160.02 364.49 0)
			(effects
				(font
					(size 1.27 1.27)
				)
				(hide yes)
			)
		)
		(property "Author" "Antmicro"
			(at 168.91 372.11 0)
			(effects
				(font
					(size 1.27 1.27)
					(thickness 0.15)
				)
				(justify left bottom)
				(hide yes)
			)
		)
		(property "License" "Apache-2.0"
			(at 168.91 374.65 0)
			(effects
				(font
					(size 1.27 1.27)
					(thickness 0.15)
				)
				(justify left bottom)
				(hide yes)
			)
		)
		(pin "1"
		)
		(instances
			(project "thunderbolt-gpu-adapter"
				(path ""
					(reference "#PWR054")
					(unit 1)
				)
			)
		)
	)
	(symbol
		(lib_id "antmicropower:GND")
		(at 233.68 224.79 0)
		(unit 1)
		(exclude_from_sim no)
		(in_bom yes)
		(on_board yes)
		(dnp no)
		(property "Reference" "#PWR0244"
			(at 233.68 231.14 0)
			(effects
				(font
					(size 1.27 1.27)
				)
				(hide yes)
			)
		)
		(property "Value" "GND"
			(at 231.775 229.235 0)
			(effects
				(font
					(size 1.27 1.27)
					(thickness 0.15)
				)
				(justify left bottom)
			)
		)
		(property "Footprint" ""
			(at 233.68 224.79 0)
			(effects
				(font
					(size 1.27 1.27)
					(thickness 0.15)
				)
				(justify left bottom)
				(hide yes)
			)
		)
		(property "Datasheet" ""
			(at 233.68 224.79 0)
			(effects
				(font
					(size 1.27 1.27)
					(thickness 0.15)
				)
				(justify left bottom)
				(hide yes)
			)
		)
		(property "Description" ""
			(at 233.68 224.79 0)
			(effects
				(font
					(size 1.27 1.27)
				)
				(hide yes)
			)
		)
		(property "Author" "Antmicro"
			(at 242.57 232.41 0)
			(effects
				(font
					(size 1.27 1.27)
					(thickness 0.15)
				)
				(justify left bottom)
				(hide yes)
			)
		)
		(property "License" "Apache-2.0"
			(at 242.57 234.95 0)
			(effects
				(font
					(size 1.27 1.27)
					(thickness 0.15)
				)
				(justify left bottom)
				(hide yes)
			)
		)
		(pin "1"
		)
		(instances
			(project "thunderbolt-gpu-adapter"
				(path ""
					(reference "#PWR0244")
					(unit 1)
				)
			)
		)
	)
	(symbol
		(lib_id "antmicropower:GND")
		(at 111.76 245.11 0)
		(unit 1)
		(exclude_from_sim no)
		(in_bom yes)
		(on_board yes)
		(dnp no)
		(property "Reference" "#PWR0233"
			(at 111.76 251.46 0)
			(effects
				(font
					(size 1.27 1.27)
				)
				(hide yes)
			)
		)
		(property "Value" "GND"
			(at 109.855 249.555 0)
			(effects
				(font
					(size 1.27 1.27)
					(thickness 0.15)
				)
				(justify left bottom)
			)
		)
		(property "Footprint" ""
			(at 111.76 245.11 0)
			(effects
				(font
					(size 1.27 1.27)
					(thickness 0.15)
				)
				(justify left bottom)
				(hide yes)
			)
		)
		(property "Datasheet" ""
			(at 111.76 245.11 0)
			(effects
				(font
					(size 1.27 1.27)
					(thickness 0.15)
				)
				(justify left bottom)
				(hide yes)
			)
		)
		(property "Description" ""
			(at 111.76 245.11 0)
			(effects
				(font
					(size 1.27 1.27)
				)
				(hide yes)
			)
		)
		(property "Author" "Antmicro"
			(at 120.65 252.73 0)
			(effects
				(font
					(size 1.27 1.27)
					(thickness 0.15)
				)
				(justify left bottom)
				(hide yes)
			)
		)
		(property "License" "Apache-2.0"
			(at 120.65 255.27 0)
			(effects
				(font
					(size 1.27 1.27)
					(thickness 0.15)
				)
				(justify left bottom)
				(hide yes)
			)
		)
		(pin "1"
		)
		(instances
			(project "thunderbolt-gpu-adapter"
				(path ""
					(reference "#PWR0233")
					(unit 1)
				)
			)
		)
	)
	(symbol
		(lib_id "antmicropower:GND")
		(at 220.98 212.09 0)
		(unit 1)
		(exclude_from_sim no)
		(in_bom yes)
		(on_board yes)
		(dnp no)
		(property "Reference" "#PWR0243"
			(at 220.98 218.44 0)
			(effects
				(font
					(size 1.27 1.27)
				)
				(hide yes)
			)
		)
		(property "Value" "GND"
			(at 219.075 216.535 0)
			(effects
				(font
					(size 1.27 1.27)
					(thickness 0.15)
				)
				(justify left bottom)
			)
		)
		(property "Footprint" ""
			(at 220.98 212.09 0)
			(effects
				(font
					(size 1.27 1.27)
					(thickness 0.15)
				)
				(justify left bottom)
				(hide yes)
			)
		)
		(property "Datasheet" ""
			(at 220.98 212.09 0)
			(effects
				(font
					(size 1.27 1.27)
					(thickness 0.15)
				)
				(justify left bottom)
				(hide yes)
			)
		)
		(property "Description" ""
			(at 220.98 212.09 0)
			(effects
				(font
					(size 1.27 1.27)
				)
				(hide yes)
			)
		)
		(property "Author" "Antmicro"
			(at 229.87 219.71 0)
			(effects
				(font
					(size 1.27 1.27)
					(thickness 0.15)
				)
				(justify left bottom)
				(hide yes)
			)
		)
		(property "License" "Apache-2.0"
			(at 229.87 222.25 0)
			(effects
				(font
					(size 1.27 1.27)
					(thickness 0.15)
				)
				(justify left bottom)
				(hide yes)
			)
		)
		(pin "1"
		)
		(instances
			(project "thunderbolt-gpu-adapter"
				(path ""
					(reference "#PWR0243")
					(unit 1)
				)
			)
		)
	)
	(symbol
		(lib_id "antmicroCapacitors0402:C_100n_0402")
		(at 92.71 337.82 90)
		(unit 1)
		(exclude_from_sim no)
		(in_bom yes)
		(on_board yes)
		(dnp no)
		(fields_autoplaced yes)
		(property "Reference" "C24"
			(at 95.25 334.0036 90)
			(effects
				(font
					(size 1.27 1.27)
					(thickness 0.15)
				)
				(justify right)
			)
		)
		(property "Value" "C_100n_0402"
			(at 102.87 317.5 0)
			(effects
				(font
					(size 1.27 1.27)
					(thickness 0.15)
				)
				(justify left bottom)
				(hide yes)
			)
		)
		(property "Footprint" "antmicro-footprints:C_0402_1005Metric"
			(at 105.41 317.5 0)
			(effects
				(font
					(size 1.27 1.27)
					(thickness 0.15)
				)
				(justify left bottom)
				(hide yes)
			)
		)
		(property "Datasheet" "https://www.murata.com/products/productdetail?partno=GRM155R61H104KE14%23"
			(at 107.95 317.5 0)
			(effects
				(font
					(size 1.27 1.27)
					(thickness 0.15)
				)
				(justify left bottom)
				(hide yes)
			)
		)
		(property "Description" ""
			(at 92.71 337.82 0)
			(effects
				(font
					(size 1.27 1.27)
				)
				(hide yes)
			)
		)
		(property "MPN" "GRM155R61H104KE14D"
			(at 110.49 317.5 0)
			(effects
				(font
					(size 1.27 1.27)
					(thickness 0.15)
				)
				(justify left bottom)
				(hide yes)
			)
		)
		(property "Manufacturer" "Murata"
			(at 113.03 317.5 0)
			(effects
				(font
					(size 1.27 1.27)
					(thickness 0.15)
				)
				(justify left bottom)
				(hide yes)
			)
		)
		(property "License" "Apache-2.0"
			(at 115.57 317.5 0)
			(effects
				(font
					(size 1.27 1.27)
					(thickness 0.15)
				)
				(justify left bottom)
				(hide yes)
			)
		)
		(property "Val" "100n"
			(at 95.25 336.5436 90)
			(effects
				(font
					(size 1.27 1.27)
					(thickness 0.15)
				)
				(justify right)
			)
		)
		(property "Voltage" "50V"
			(at 120.65 317.5 0)
			(effects
				(font
					(size 1.27 1.27)
				)
				(justify left bottom)
				(hide yes)
			)
		)
		(property "Dielectric" "X5R"
			(at 123.19 317.5 0)
			(effects
				(font
					(size 1.27 1.27)
				)
				(justify left bottom)
				(hide yes)
			)
		)
		(property "Author" "Antmicro"
			(at 118.11 317.5 0)
			(effects
				(font
					(size 1.27 1.27)
					(thickness 0.15)
				)
				(justify left bottom)
				(hide yes)
			)
		)
		(pin "1"
		)
		(pin "2"
		)
		(instances
			(project "thunderbolt-gpu-adapter"
				(path ""
					(reference "C24")
					(unit 1)
				)
			)
		)
	)
	(symbol
		(lib_id "antmicroResistors0402:R_1k_0402")
		(at 222.25 80.01 0)
		(unit 1)
		(exclude_from_sim no)
		(in_bom yes)
		(on_board yes)
		(dnp no)
		(fields_autoplaced yes)
		(property "Reference" "R120"
			(at 224.79 73.66 0)
			(effects
				(font
					(size 1.27 1.27)
					(thickness 0.15)
				)
			)
		)
		(property "Value" "R_1k_0402"
			(at 242.57 92.71 0)
			(effects
				(font
					(size 1.27 1.27)
					(thickness 0.15)
				)
				(justify left bottom)
				(hide yes)
			)
		)
		(property "Footprint" "antmicro-footprints:R_0402_1005Metric"
			(at 242.57 95.25 0)
			(effects
				(font
					(size 1.27 1.27)
					(thickness 0.15)
				)
				(justify left bottom)
				(hide yes)
			)
		)
		(property "Datasheet" "https://www.bourns.com/docs/product-datasheets/cr.pdf"
			(at 242.57 97.79 0)
			(effects
				(font
					(size 1.27 1.27)
					(thickness 0.15)
				)
				(justify left bottom)
				(hide yes)
			)
		)
		(property "Description" ""
			(at 222.25 80.01 0)
			(effects
				(font
					(size 1.27 1.27)
				)
				(hide yes)
			)
		)
		(property "MPN" "CR0402-FX-1001GLF"
			(at 242.57 100.33 0)
			(effects
				(font
					(size 1.27 1.27)
					(thickness 0.15)
				)
				(justify left bottom)
				(hide yes)
			)
		)
		(property "Manufacturer" "Bourns"
			(at 242.57 102.87 0)
			(effects
				(font
					(size 1.27 1.27)
					(thickness 0.15)
				)
				(justify left bottom)
				(hide yes)
			)
		)
		(property "License" "Apache-2.0"
			(at 242.57 105.41 0)
			(effects
				(font
					(size 1.27 1.27)
					(thickness 0.15)
				)
				(justify left bottom)
				(hide yes)
			)
		)
		(property "Val" "1k"
			(at 224.79 76.2 0)
			(effects
				(font
					(size 1.27 1.27)
					(thickness 0.15)
				)
			)
		)
		(property "Tolerance" "1%"
			(at 242.57 90.17 0)
			(effects
				(font
					(size 1.27 1.27)
				)
				(justify left bottom)
				(hide yes)
			)
		)
		(property "Author" "Antmicro"
			(at 242.57 107.95 0)
			(effects
				(font
					(size 1.27 1.27)
					(thickness 0.15)
				)
				(justify left bottom)
				(hide yes)
			)
		)
		(pin "1"
		)
		(pin "2"
		)
		(instances
			(project "thunderbolt-gpu-adapter"
				(path ""
					(reference "R120")
					(unit 1)
				)
			)
		)
	)
	(symbol
		(lib_id "antmicroResistors0402:R_100k_0402")
		(at 46.99 165.1 90)
		(unit 1)
		(exclude_from_sim no)
		(in_bom yes)
		(on_board yes)
		(dnp no)
		(fields_autoplaced yes)
		(property "Reference" "R9"
			(at 44.45 161.29 90)
			(effects
				(font
					(size 1.27 1.27)
					(thickness 0.15)
				)
				(justify left)
			)
		)
		(property "Value" "R_100k_0402"
			(at 59.69 144.78 0)
			(effects
				(font
					(size 1.27 1.27)
					(thickness 0.15)
				)
				(justify left bottom)
				(hide yes)
			)
		)
		(property "Footprint" "antmicro-footprints:R_0402_1005Metric"
			(at 62.23 144.78 0)
			(effects
				(font
					(size 1.27 1.27)
					(thickness 0.15)
				)
				(justify left bottom)
				(hide yes)
			)
		)
		(property "Datasheet" "https://www.bourns.com/docs/product-datasheets/cr.pdf"
			(at 64.77 144.78 0)
			(effects
				(font
					(size 1.27 1.27)
					(thickness 0.15)
				)
				(justify left bottom)
				(hide yes)
			)
		)
		(property "Description" ""
			(at 46.99 165.1 0)
			(effects
				(font
					(size 1.27 1.27)
				)
				(hide yes)
			)
		)
		(property "MPN" "CR0402-FX-1003GLF"
			(at 67.31 144.78 0)
			(effects
				(font
					(size 1.27 1.27)
					(thickness 0.15)
				)
				(justify left bottom)
				(hide yes)
			)
		)
		(property "Manufacturer" "Bourns"
			(at 69.85 144.78 0)
			(effects
				(font
					(size 1.27 1.27)
					(thickness 0.15)
				)
				(justify left bottom)
				(hide yes)
			)
		)
		(property "License" "Apache-2.0"
			(at 72.39 144.78 0)
			(effects
				(font
					(size 1.27 1.27)
					(thickness 0.15)
				)
				(justify left bottom)
				(hide yes)
			)
		)
		(property "Val" "100k"
			(at 44.45 163.83 90)
			(effects
				(font
					(size 1.27 1.27)
					(thickness 0.15)
				)
				(justify left)
			)
		)
		(property "Tolerance" "1%"
			(at 57.15 144.78 0)
			(effects
				(font
					(size 1.27 1.27)
				)
				(justify left bottom)
				(hide yes)
			)
		)
		(property "Author" "Antmicro"
			(at 74.93 144.78 0)
			(effects
				(font
					(size 1.27 1.27)
					(thickness 0.15)
				)
				(justify left bottom)
				(hide yes)
			)
		)
		(pin "1"
		)
		(pin "2"
		)
		(instances
			(project "thunderbolt-gpu-adapter"
				(path ""
					(reference "R9")
					(unit 1)
				)
			)
		)
	)
	(symbol
		(lib_id "antmicroCapacitorsmisc:C_22u_1206_35V")
		(at 45.72 204.47 90)
		(unit 1)
		(exclude_from_sim no)
		(in_bom yes)
		(on_board yes)
		(dnp yes)
		(fields_autoplaced yes)
		(property "Reference" "C8"
			(at 48.26 200.6536 90)
			(effects
				(font
					(size 1.27 1.27)
					(thickness 0.15)
				)
				(justify right)
			)
		)
		(property "Value" "C_22u_1206_35V"
			(at 55.88 184.15 0)
			(effects
				(font
					(size 1.27 1.27)
					(thickness 0.15)
				)
				(justify left bottom)
				(hide yes)
			)
		)
		(property "Footprint" "antmicro-footprints:C_1206_3216Metric"
			(at 58.42 184.15 0)
			(effects
				(font
					(size 1.27 1.27)
					(thickness 0.15)
				)
				(justify left bottom)
				(hide yes)
			)
		)
		(property "Datasheet" "https://product.tdk.com/en/search/capacitor/ceramic/mlcc/info?part_no=3216X5R1V226M160AC"
			(at 60.96 184.15 0)
			(effects
				(font
					(size 1.27 1.27)
					(thickness 0.15)
				)
				(justify left bottom)
				(hide yes)
			)
		)
		(property "Description" ""
			(at 45.72 204.47 0)
			(effects
				(font
					(size 1.27 1.27)
				)
				(hide yes)
			)
		)
		(property "MPN" "3216X5R1V226M160AC"
			(at 63.5 184.15 0)
			(effects
				(font
					(size 1.27 1.27)
					(thickness 0.15)
				)
				(justify left bottom)
				(hide yes)
			)
		)
		(property "Manufacturer" "TDK"
			(at 66.04 184.15 0)
			(effects
				(font
					(size 1.27 1.27)
					(thickness 0.15)
				)
				(justify left bottom)
				(hide yes)
			)
		)
		(property "License" "Apache-2.0"
			(at 68.58 184.15 0)
			(effects
				(font
					(size 1.27 1.27)
					(thickness 0.15)
				)
				(justify left bottom)
				(hide yes)
			)
		)
		(property "Val" "22u"
			(at 48.26 203.1936 90)
			(effects
				(font
					(size 1.27 1.27)
					(thickness 0.15)
				)
				(justify right)
			)
		)
		(property "Voltage" "35V"
			(at 73.66 184.15 0)
			(effects
				(font
					(size 1.27 1.27)
				)
				(justify left bottom)
				(hide yes)
			)
		)
		(property "Dielectric" ""
			(at 76.2 184.15 0)
			(effects
				(font
					(size 1.27 1.27)
				)
				(justify left bottom)
				(hide yes)
			)
		)
		(property "Author" "Antmicro"
			(at 71.12 184.15 0)
			(effects
				(font
					(size 1.27 1.27)
					(thickness 0.15)
				)
				(justify left bottom)
				(hide yes)
			)
		)
		(pin "1"
		)
		(pin "2"
		)
		(instances
			(project "thunderbolt-gpu-adapter"
				(path ""
					(reference "C8")
					(unit 1)
				)
			)
		)
	)
	(symbol
		(lib_id "antmicroResistorsmisc:R_0R02_1206")
		(at 242.57 203.2 0)
		(unit 1)
		(exclude_from_sim no)
		(in_bom yes)
		(on_board yes)
		(dnp no)
		(fields_autoplaced yes)
		(property "Reference" "R45"
			(at 245.11 196.85 0)
			(effects
				(font
					(size 1.27 1.27)
					(thickness 0.15)
				)
			)
		)
		(property "Value" "R_0R02_1206"
			(at 262.89 215.9 0)
			(effects
				(font
					(size 1.27 1.27)
					(thickness 0.15)
				)
				(justify left bottom)
				(hide yes)
			)
		)
		(property "Footprint" "antmicro-footprints:R_1206_3216Metric"
			(at 262.89 218.44 0)
			(effects
				(font
					(size 1.27 1.27)
					(thickness 0.15)
				)
				(justify left bottom)
				(hide yes)
			)
		)
		(property "Datasheet" "https://www.mouser.com/datasheet/2/427/wslp-1763037.pdf"
			(at 262.89 220.98 0)
			(effects
				(font
					(size 1.27 1.27)
					(thickness 0.15)
				)
				(justify left bottom)
				(hide yes)
			)
		)
		(property "Description" ""
			(at 242.57 203.2 0)
			(effects
				(font
					(size 1.27 1.27)
				)
				(hide yes)
			)
		)
		(property "MPN" "WSLP1206R0200FEA"
			(at 262.89 223.52 0)
			(effects
				(font
					(size 1.27 1.27)
					(thickness 0.15)
				)
				(justify left bottom)
				(hide yes)
			)
		)
		(property "Manufacturer" "Vishay"
			(at 262.89 226.06 0)
			(effects
				(font
					(size 1.27 1.27)
					(thickness 0.15)
				)
				(justify left bottom)
				(hide yes)
			)
		)
		(property "License" "Apache-2.0"
			(at 262.89 228.6 0)
			(effects
				(font
					(size 1.27 1.27)
					(thickness 0.15)
				)
				(justify left bottom)
				(hide yes)
			)
		)
		(property "Val" "0R02"
			(at 245.11 199.39 0)
			(effects
				(font
					(size 1.27 1.27)
					(thickness 0.15)
				)
			)
		)
		(property "Tolerance" "1%"
			(at 262.89 213.36 0)
			(effects
				(font
					(size 1.27 1.27)
				)
				(justify left bottom)
				(hide yes)
			)
		)
		(property "Author" "Antmicro"
			(at 262.89 231.14 0)
			(effects
				(font
					(size 1.27 1.27)
					(thickness 0.15)
				)
				(justify left bottom)
				(hide yes)
			)
		)
		(pin "1"
		)
		(pin "2"
		)
		(instances
			(project "thunderbolt-gpu-adapter"
				(path ""
					(reference "R45")
					(unit 1)
				)
			)
		)
	)
	(symbol
		(lib_id "antmicropower:GND")
		(at 55.88 267.97 0)
		(unit 1)
		(exclude_from_sim no)
		(in_bom yes)
		(on_board yes)
		(dnp no)
		(property "Reference" "#PWR0164"
			(at 55.88 274.32 0)
			(effects
				(font
					(size 1.27 1.27)
				)
				(hide yes)
			)
		)
		(property "Value" "GND"
			(at 55.88 271.78 0)
			(effects
				(font
					(size 1.27 1.27)
				)
			)
		)
		(property "Footprint" ""
			(at 55.88 267.97 0)
			(effects
				(font
					(size 1.27 1.27)
				)
				(hide yes)
			)
		)
		(property "Datasheet" ""
			(at 55.88 267.97 0)
			(effects
				(font
					(size 1.27 1.27)
				)
				(hide yes)
			)
		)
		(property "Description" ""
			(at 55.88 267.97 0)
			(effects
				(font
					(size 1.27 1.27)
				)
				(hide yes)
			)
		)
		(property "Author" "Antmicro"
			(at 64.77 275.59 0)
			(effects
				(font
					(size 1.27 1.27)
					(thickness 0.15)
				)
				(justify left bottom)
				(hide yes)
			)
		)
		(property "License" "Apache-2.0"
			(at 64.77 278.13 0)
			(effects
				(font
					(size 1.27 1.27)
					(thickness 0.15)
				)
				(justify left bottom)
				(hide yes)
			)
		)
		(pin "1"
		)
		(instances
			(project "thunderbolt-gpu-adapter"
				(path ""
					(reference "#PWR0164")
					(unit 1)
				)
			)
		)
	)
	(symbol
		(lib_id "antmicroCapacitors0402:C_2u2_0402")
		(at 133.35 69.85 0)
		(unit 1)
		(exclude_from_sim no)
		(in_bom yes)
		(on_board yes)
		(dnp no)
		(property "Reference" "C37"
			(at 138.43 68.58 0)
			(effects
				(font
					(size 1.27 1.27)
					(thickness 0.15)
				)
			)
		)
		(property "Value" "C_2u2_0402"
			(at 153.67 80.01 0)
			(effects
				(font
					(size 1.27 1.27)
					(thickness 0.15)
				)
				(justify left bottom)
				(hide yes)
			)
		)
		(property "Footprint" "antmicro-footprints:C_0402_1005Metric"
			(at 153.67 82.55 0)
			(effects
				(font
					(size 1.27 1.27)
					(thickness 0.15)
				)
				(justify left bottom)
				(hide yes)
			)
		)
		(property "Datasheet" "https://product.tdk.com/en/search/capacitor/ceramic/mlcc/info?part_no=C1005X5R1A225K050BC"
			(at 153.67 85.09 0)
			(effects
				(font
					(size 1.27 1.27)
					(thickness 0.15)
				)
				(justify left bottom)
				(hide yes)
			)
		)
		(property "Description" ""
			(at 133.35 69.85 0)
			(effects
				(font
					(size 1.27 1.27)
				)
				(hide yes)
			)
		)
		(property "MPN" "C1005X5R1A225K050BC"
			(at 153.67 87.63 0)
			(effects
				(font
					(size 1.27 1.27)
					(thickness 0.15)
				)
				(justify left bottom)
				(hide yes)
			)
		)
		(property "Manufacturer" "TDK"
			(at 153.67 90.17 0)
			(effects
				(font
					(size 1.27 1.27)
					(thickness 0.15)
				)
				(justify left bottom)
				(hide yes)
			)
		)
		(property "License" "Apache-2.0"
			(at 153.67 92.71 0)
			(effects
				(font
					(size 1.27 1.27)
					(thickness 0.15)
				)
				(justify left bottom)
				(hide yes)
			)
		)
		(property "Val" "2u2"
			(at 138.43 71.12 0)
			(effects
				(font
					(size 1.27 1.27)
					(thickness 0.15)
				)
			)
		)
		(property "Voltage" ""
			(at 153.67 97.79 0)
			(effects
				(font
					(size 1.27 1.27)
				)
				(justify left bottom)
				(hide yes)
			)
		)
		(property "Dielectric" ""
			(at 153.67 100.33 0)
			(effects
				(font
					(size 1.27 1.27)
				)
				(justify left bottom)
				(hide yes)
			)
		)
		(property "Author" "Antmicro"
			(at 153.67 95.25 0)
			(effects
				(font
					(size 1.27 1.27)
					(thickness 0.15)
				)
				(justify left bottom)
				(hide yes)
			)
		)
		(pin "1"
		)
		(pin "2"
		)
		(instances
			(project "thunderbolt-gpu-adapter"
				(path ""
					(reference "C37")
					(unit 1)
				)
			)
		)
	)
	(symbol
		(lib_id "antmicropower:GND")
		(at 137.16 85.09 0)
		(unit 1)
		(exclude_from_sim no)
		(in_bom yes)
		(on_board yes)
		(dnp no)
		(property "Reference" "#PWR045"
			(at 137.16 91.44 0)
			(effects
				(font
					(size 1.27 1.27)
				)
				(hide yes)
			)
		)
		(property "Value" "GND"
			(at 137.16 88.9 0)
			(effects
				(font
					(size 1.27 1.27)
				)
			)
		)
		(property "Footprint" ""
			(at 137.16 85.09 0)
			(effects
				(font
					(size 1.27 1.27)
				)
				(hide yes)
			)
		)
		(property "Datasheet" ""
			(at 137.16 85.09 0)
			(effects
				(font
					(size 1.27 1.27)
				)
				(hide yes)
			)
		)
		(property "Description" ""
			(at 137.16 85.09 0)
			(effects
				(font
					(size 1.27 1.27)
				)
				(hide yes)
			)
		)
		(property "Author" "Antmicro"
			(at 146.05 92.71 0)
			(effects
				(font
					(size 1.27 1.27)
					(thickness 0.15)
				)
				(justify left bottom)
				(hide yes)
			)
		)
		(property "License" "Apache-2.0"
			(at 146.05 95.25 0)
			(effects
				(font
					(size 1.27 1.27)
					(thickness 0.15)
				)
				(justify left bottom)
				(hide yes)
			)
		)
		(pin "1"
		)
		(instances
			(project "thunderbolt-gpu-adapter"
				(path ""
					(reference "#PWR045")
					(unit 1)
				)
			)
		)
	)
	(symbol
		(lib_id "antmicroResistors0402:R_100k_0402")
		(at 43.18 110.49 90)
		(unit 1)
		(exclude_from_sim no)
		(in_bom yes)
		(on_board yes)
		(dnp no)
		(property "Reference" "R4"
			(at 44.45 106.68 90)
			(effects
				(font
					(size 1.27 1.27)
					(thickness 0.15)
				)
				(justify right)
			)
		)
		(property "Value" "R_100k_0402"
			(at 55.88 90.17 0)
			(effects
				(font
					(size 1.27 1.27)
					(thickness 0.15)
				)
				(justify left bottom)
				(hide yes)
			)
		)
		(property "Footprint" "antmicro-footprints:R_0402_1005Metric"
			(at 58.42 90.17 0)
			(effects
				(font
					(size 1.27 1.27)
					(thickness 0.15)
				)
				(justify left bottom)
				(hide yes)
			)
		)
		(property "Datasheet" "https://www.bourns.com/docs/product-datasheets/cr.pdf"
			(at 60.96 90.17 0)
			(effects
				(font
					(size 1.27 1.27)
					(thickness 0.15)
				)
				(justify left bottom)
				(hide yes)
			)
		)
		(property "Description" ""
			(at 43.18 110.49 0)
			(effects
				(font
					(size 1.27 1.27)
				)
				(hide yes)
			)
		)
		(property "MPN" "CR0402-FX-1003GLF"
			(at 63.5 90.17 0)
			(effects
				(font
					(size 1.27 1.27)
					(thickness 0.15)
				)
				(justify left bottom)
				(hide yes)
			)
		)
		(property "Manufacturer" "Bourns"
			(at 66.04 90.17 0)
			(effects
				(font
					(size 1.27 1.27)
					(thickness 0.15)
				)
				(justify left bottom)
				(hide yes)
			)
		)
		(property "License" "Apache-2.0"
			(at 68.58 90.17 0)
			(effects
				(font
					(size 1.27 1.27)
					(thickness 0.15)
				)
				(justify left bottom)
				(hide yes)
			)
		)
		(property "Val" "100k"
			(at 44.45 109.22 90)
			(effects
				(font
					(size 1.27 1.27)
					(thickness 0.15)
				)
				(justify right)
			)
		)
		(property "Tolerance" "1%"
			(at 53.34 90.17 0)
			(effects
				(font
					(size 1.27 1.27)
				)
				(justify left bottom)
				(hide yes)
			)
		)
		(property "Author" "Antmicro"
			(at 71.12 90.17 0)
			(effects
				(font
					(size 1.27 1.27)
					(thickness 0.15)
				)
				(justify left bottom)
				(hide yes)
			)
		)
		(pin "1"
		)
		(pin "2"
		)
		(instances
			(project "thunderbolt-gpu-adapter"
				(path ""
					(reference "R4")
					(unit 1)
				)
			)
		)
	)
	(symbol
		(lib_id "antmicroResistors0402:R_24k_0402")
		(at 96.52 204.47 90)
		(unit 1)
		(exclude_from_sim no)
		(in_bom yes)
		(on_board yes)
		(dnp no)
		(fields_autoplaced yes)
		(property "Reference" "R7"
			(at 99.06 200.66 90)
			(effects
				(font
					(size 1.27 1.27)
					(thickness 0.15)
				)
				(justify right)
			)
		)
		(property "Value" "R_24k_0402"
			(at 109.22 184.15 0)
			(effects
				(font
					(size 1.27 1.27)
					(thickness 0.15)
				)
				(justify left bottom)
				(hide yes)
			)
		)
		(property "Footprint" "antmicro-footprints:R_0402_1005Metric"
			(at 111.76 184.15 0)
			(effects
				(font
					(size 1.27 1.27)
					(thickness 0.15)
				)
				(justify left bottom)
				(hide yes)
			)
		)
		(property "Datasheet" "https://www.bourns.com/docs/product-datasheets/cr.pdf"
			(at 114.3 184.15 0)
			(effects
				(font
					(size 1.27 1.27)
					(thickness 0.15)
				)
				(justify left bottom)
				(hide yes)
			)
		)
		(property "Description" ""
			(at 96.52 204.47 0)
			(effects
				(font
					(size 1.27 1.27)
				)
				(hide yes)
			)
		)
		(property "MPN" "CR0402-FX-2402GLF"
			(at 116.84 184.15 0)
			(effects
				(font
					(size 1.27 1.27)
					(thickness 0.15)
				)
				(justify left bottom)
				(hide yes)
			)
		)
		(property "Manufacturer" "Bourns"
			(at 119.38 184.15 0)
			(effects
				(font
					(size 1.27 1.27)
					(thickness 0.15)
				)
				(justify left bottom)
				(hide yes)
			)
		)
		(property "License" "Apache-2.0"
			(at 121.92 184.15 0)
			(effects
				(font
					(size 1.27 1.27)
					(thickness 0.15)
				)
				(justify left bottom)
				(hide yes)
			)
		)
		(property "Val" "24k"
			(at 99.06 203.2 90)
			(effects
				(font
					(size 1.27 1.27)
					(thickness 0.15)
				)
				(justify right)
			)
		)
		(property "Tolerance" "1%"
			(at 106.68 184.15 0)
			(effects
				(font
					(size 1.27 1.27)
				)
				(justify left bottom)
				(hide yes)
			)
		)
		(property "Author" "Antmicro"
			(at 124.46 184.15 0)
			(effects
				(font
					(size 1.27 1.27)
					(thickness 0.15)
				)
				(justify left bottom)
				(hide yes)
			)
		)
		(pin "1"
		)
		(pin "2"
		)
		(instances
			(project "thunderbolt-gpu-adapter"
				(path ""
					(reference "R7")
					(unit 1)
				)
			)
		)
	)
	(symbol
		(lib_id "antmicropower:GND")
		(at 250.19 326.39 0)
		(unit 1)
		(exclude_from_sim no)
		(in_bom yes)
		(on_board yes)
		(dnp no)
		(property "Reference" "#PWR0154"
			(at 250.19 332.74 0)
			(effects
				(font
					(size 1.27 1.27)
				)
				(hide yes)
			)
		)
		(property "Value" "GND"
			(at 250.19 330.2 0)
			(effects
				(font
					(size 1.27 1.27)
				)
			)
		)
		(property "Footprint" ""
			(at 250.19 326.39 0)
			(effects
				(font
					(size 1.27 1.27)
				)
				(hide yes)
			)
		)
		(property "Datasheet" ""
			(at 250.19 326.39 0)
			(effects
				(font
					(size 1.27 1.27)
				)
				(hide yes)
			)
		)
		(property "Description" ""
			(at 250.19 326.39 0)
			(effects
				(font
					(size 1.27 1.27)
				)
				(hide yes)
			)
		)
		(property "Author" "Antmicro"
			(at 259.08 334.01 0)
			(effects
				(font
					(size 1.27 1.27)
					(thickness 0.15)
				)
				(justify left bottom)
				(hide yes)
			)
		)
		(property "License" "Apache-2.0"
			(at 259.08 336.55 0)
			(effects
				(font
					(size 1.27 1.27)
					(thickness 0.15)
				)
				(justify left bottom)
				(hide yes)
			)
		)
		(pin "1"
		)
		(instances
			(project "thunderbolt-gpu-adapter"
				(path ""
					(reference "#PWR0154")
					(unit 1)
				)
			)
		)
	)
	(symbol
		(lib_id "antmicropower:GND")
		(at 224.79 287.02 0)
		(unit 1)
		(exclude_from_sim no)
		(in_bom yes)
		(on_board yes)
		(dnp no)
		(property "Reference" "#PWR0158"
			(at 224.79 293.37 0)
			(effects
				(font
					(size 1.27 1.27)
				)
				(hide yes)
			)
		)
		(property "Value" "GND"
			(at 224.79 290.83 0)
			(effects
				(font
					(size 1.27 1.27)
				)
			)
		)
		(property "Footprint" ""
			(at 224.79 287.02 0)
			(effects
				(font
					(size 1.27 1.27)
				)
				(hide yes)
			)
		)
		(property "Datasheet" ""
			(at 224.79 287.02 0)
			(effects
				(font
					(size 1.27 1.27)
				)
				(hide yes)
			)
		)
		(property "Description" ""
			(at 224.79 287.02 0)
			(effects
				(font
					(size 1.27 1.27)
				)
				(hide yes)
			)
		)
		(property "Author" "Antmicro"
			(at 233.68 294.64 0)
			(effects
				(font
					(size 1.27 1.27)
					(thickness 0.15)
				)
				(justify left bottom)
				(hide yes)
			)
		)
		(property "License" "Apache-2.0"
			(at 233.68 297.18 0)
			(effects
				(font
					(size 1.27 1.27)
					(thickness 0.15)
				)
				(justify left bottom)
				(hide yes)
			)
		)
		(pin "1"
		)
		(instances
			(project "thunderbolt-gpu-adapter"
				(path ""
					(reference "#PWR0158")
					(unit 1)
				)
			)
		)
	)
	(symbol
		(lib_id "antmicropower:PWR_FLAG")
		(at 237.49 345.44 0)
		(unit 1)
		(exclude_from_sim no)
		(in_bom yes)
		(on_board yes)
		(dnp no)
		(fields_autoplaced yes)
		(property "Reference" "#FLG0103"
			(at 237.49 343.535 0)
			(effects
				(font
					(size 1.27 1.27)
				)
				(hide yes)
			)
		)
		(property "Value" "PWR_FLAG"
			(at 237.49 340.36 0)
			(effects
				(font
					(size 1.27 1.27)
				)
			)
		)
		(property "Footprint" ""
			(at 237.49 345.44 0)
			(effects
				(font
					(size 1.27 1.27)
				)
				(hide yes)
			)
		)
		(property "Datasheet" ""
			(at 237.49 345.44 0)
			(effects
				(font
					(size 1.27 1.27)
				)
				(hide yes)
			)
		)
		(property "Description" ""
			(at 237.49 345.44 0)
			(effects
				(font
					(size 1.27 1.27)
				)
				(hide yes)
			)
		)
		(pin "1"
		)
		(instances
			(project "thunderbolt-gpu-adapter"
				(path ""
					(reference "#FLG0103")
					(unit 1)
				)
			)
		)
	)
	(symbol
		(lib_id "antmicropower:GND")
		(at 262.89 215.9 0)
		(unit 1)
		(exclude_from_sim no)
		(in_bom yes)
		(on_board yes)
		(dnp no)
		(property "Reference" "#PWR0245"
			(at 262.89 222.25 0)
			(effects
				(font
					(size 1.27 1.27)
				)
				(hide yes)
			)
		)
		(property "Value" "GND"
			(at 260.985 220.345 0)
			(effects
				(font
					(size 1.27 1.27)
					(thickness 0.15)
				)
				(justify left bottom)
			)
		)
		(property "Footprint" ""
			(at 262.89 215.9 0)
			(effects
				(font
					(size 1.27 1.27)
					(thickness 0.15)
				)
				(justify left bottom)
				(hide yes)
			)
		)
		(property "Datasheet" ""
			(at 262.89 215.9 0)
			(effects
				(font
					(size 1.27 1.27)
					(thickness 0.15)
				)
				(justify left bottom)
				(hide yes)
			)
		)
		(property "Description" ""
			(at 262.89 215.9 0)
			(effects
				(font
					(size 1.27 1.27)
				)
				(hide yes)
			)
		)
		(property "Author" "Antmicro"
			(at 271.78 223.52 0)
			(effects
				(font
					(size 1.27 1.27)
					(thickness 0.15)
				)
				(justify left bottom)
				(hide yes)
			)
		)
		(property "License" "Apache-2.0"
			(at 271.78 226.06 0)
			(effects
				(font
					(size 1.27 1.27)
					(thickness 0.15)
				)
				(justify left bottom)
				(hide yes)
			)
		)
		(pin "1"
		)
		(instances
			(project "thunderbolt-gpu-adapter"
				(path ""
					(reference "#PWR0245")
					(unit 1)
				)
			)
		)
	)
	(symbol
		(lib_id "antmicroCapacitorsmisc:C_10u_0805_35V")
		(at 46.99 392.43 90)
		(unit 1)
		(exclude_from_sim no)
		(in_bom yes)
		(on_board yes)
		(dnp no)
		(property "Reference" "C127"
			(at 39.37 388.62 90)
			(effects
				(font
					(size 1.27 1.27)
					(thickness 0.15)
				)
				(justify right)
			)
		)
		(property "Value" "C_10u_0805_35V"
			(at 57.15 372.11 0)
			(effects
				(font
					(size 1.27 1.27)
					(thickness 0.15)
				)
				(justify left bottom)
				(hide yes)
			)
		)
		(property "Footprint" "antmicro-footprints:C_0805_2012Metric"
			(at 59.69 372.11 0)
			(effects
				(font
					(size 1.27 1.27)
					(thickness 0.15)
				)
				(justify left bottom)
				(hide yes)
			)
		)
		(property "Datasheet" "https://www.murata.com/products/productdetail?partno=GRM21BR6YA106KE43%23"
			(at 62.23 372.11 0)
			(effects
				(font
					(size 1.27 1.27)
					(thickness 0.15)
				)
				(justify left bottom)
				(hide yes)
			)
		)
		(property "Description" ""
			(at 46.99 392.43 0)
			(effects
				(font
					(size 1.27 1.27)
				)
				(hide yes)
			)
		)
		(property "MPN" "GRM21BR6YA106KE43L"
			(at 64.77 372.11 0)
			(effects
				(font
					(size 1.27 1.27)
					(thickness 0.15)
				)
				(justify left bottom)
				(hide yes)
			)
		)
		(property "Manufacturer" "Murata"
			(at 67.31 372.11 0)
			(effects
				(font
					(size 1.27 1.27)
					(thickness 0.15)
				)
				(justify left bottom)
				(hide yes)
			)
		)
		(property "License" "Apache-2.0"
			(at 69.85 372.11 0)
			(effects
				(font
					(size 1.27 1.27)
					(thickness 0.15)
				)
				(justify left bottom)
				(hide yes)
			)
		)
		(property "Val" "10u"
			(at 39.37 391.16 90)
			(effects
				(font
					(size 1.27 1.27)
					(thickness 0.15)
				)
				(justify right)
			)
		)
		(property "Voltage" "35V"
			(at 74.93 372.11 0)
			(effects
				(font
					(size 1.27 1.27)
				)
				(justify left bottom)
				(hide yes)
			)
		)
		(property "Dielectric" ""
			(at 77.47 372.11 0)
			(effects
				(font
					(size 1.27 1.27)
				)
				(justify left bottom)
				(hide yes)
			)
		)
		(property "Author" "Antmicro"
			(at 72.39 372.11 0)
			(effects
				(font
					(size 1.27 1.27)
					(thickness 0.15)
				)
				(justify left bottom)
				(hide yes)
			)
		)
		(pin "1"
		)
		(pin "2"
		)
		(instances
			(project "thunderbolt-gpu-adapter"
				(path ""
					(reference "C127")
					(unit 1)
				)
			)
		)
	)
	(symbol
		(lib_id "antmicroResistors0402:R_2k2_0402")
		(at 246.38 121.92 270)
		(unit 1)
		(exclude_from_sim no)
		(in_bom yes)
		(on_board yes)
		(dnp no)
		(property "Reference" "R134"
			(at 247.65 123.19 90)
			(effects
				(font
					(size 1.27 1.27)
					(thickness 0.15)
				)
				(justify left)
			)
		)
		(property "Value" "R_2k2_0402"
			(at 233.68 142.24 0)
			(effects
				(font
					(size 1.27 1.27)
					(thickness 0.15)
				)
				(justify left bottom)
				(hide yes)
			)
		)
		(property "Footprint" "antmicro-footprints:R_0402_1005Metric"
			(at 231.14 142.24 0)
			(effects
				(font
					(size 1.27 1.27)
					(thickness 0.15)
				)
				(justify left bottom)
				(hide yes)
			)
		)
		(property "Datasheet" "https://www.bourns.com/docs/product-datasheets/cr.pdf"
			(at 228.6 142.24 0)
			(effects
				(font
					(size 1.27 1.27)
					(thickness 0.15)
				)
				(justify left bottom)
				(hide yes)
			)
		)
		(property "Description" ""
			(at 246.38 121.92 0)
			(effects
				(font
					(size 1.27 1.27)
				)
				(hide yes)
			)
		)
		(property "MPN" "CR0402-FX-2201GLF"
			(at 226.06 142.24 0)
			(effects
				(font
					(size 1.27 1.27)
					(thickness 0.15)
				)
				(justify left bottom)
				(hide yes)
			)
		)
		(property "Manufacturer" "Bourns"
			(at 223.52 142.24 0)
			(effects
				(font
					(size 1.27 1.27)
					(thickness 0.15)
				)
				(justify left bottom)
				(hide yes)
			)
		)
		(property "License" "Apache-2.0"
			(at 220.98 142.24 0)
			(effects
				(font
					(size 1.27 1.27)
					(thickness 0.15)
				)
				(justify left bottom)
				(hide yes)
			)
		)
		(property "Author" "Antmicro"
			(at 218.44 142.24 0)
			(effects
				(font
					(size 1.27 1.27)
					(thickness 0.15)
				)
				(justify left bottom)
				(hide yes)
			)
		)
		(property "Val" "2k2"
			(at 247.65 125.73 90)
			(effects
				(font
					(size 1.27 1.27)
					(thickness 0.15)
				)
				(justify left)
			)
		)
		(property "Tolerance" "1%"
			(at 236.22 142.24 0)
			(effects
				(font
					(size 1.27 1.27)
				)
				(justify left bottom)
				(hide yes)
			)
		)
		(pin "1"
		)
		(pin "2"
		)
		(instances
			(project "thunderbolt-gpu-adapter"
				(path ""
					(reference "R134")
					(unit 1)
				)
			)
		)
	)
	(symbol
		(lib_id "antmicroPMICVoltageRegulatorsLinear:LM1117MP-3.3_NOPB")
		(at 53.34 384.81 0)
		(unit 1)
		(exclude_from_sim no)
		(in_bom yes)
		(on_board yes)
		(dnp no)
		(fields_autoplaced yes)
		(property "Reference" "U9"
			(at 62.23 377.19 0)
			(effects
				(font
					(size 1.27 1.27)
					(thickness 0.15)
				)
			)
		)
		(property "Value" "LM1117MP-3.3_NOPB"
			(at 86.36 392.43 0)
			(effects
				(font
					(size 1.27 1.27)
					(thickness 0.15)
				)
				(justify left bottom)
				(hide yes)
			)
		)
		(property "Footprint" "antmicro-footprints:SOT-223"
			(at 86.36 394.97 0)
			(effects
				(font
					(size 1.27 1.27)
					(thickness 0.15)
				)
				(justify left bottom)
				(hide yes)
			)
		)
		(property "Datasheet" "https://www.ti.com/lit/ds/symlink/lm1117.pdf?ts=1695352253515&ref_url=https%253A%252F%252Fwww.google.com%252F"
			(at 86.36 397.51 0)
			(effects
				(font
					(size 1.27 1.27)
					(thickness 0.15)
				)
				(justify left bottom)
				(hide yes)
			)
		)
		(property "Description" ""
			(at 53.34 384.81 0)
			(effects
				(font
					(size 1.27 1.27)
				)
				(hide yes)
			)
		)
		(property "Author" "Antmicro"
			(at 86.36 400.05 0)
			(effects
				(font
					(size 1.27 1.27)
					(thickness 0.15)
				)
				(justify left bottom)
				(hide yes)
			)
		)
		(property "License" "Apache-2.0"
			(at 86.36 402.59 0)
			(effects
				(font
					(size 1.27 1.27)
					(thickness 0.15)
				)
				(justify left bottom)
				(hide yes)
			)
		)
		(property "MPN" "LM1117IMP-3.3/NOPB"
			(at 62.23 379.73 0)
			(effects
				(font
					(size 1.27 1.27)
					(thickness 0.15)
				)
			)
		)
		(property "Manufacturer" "Texas Instruments"
			(at 86.36 405.13 0)
			(effects
				(font
					(size 1.27 1.27)
					(thickness 0.15)
				)
				(justify left bottom)
				(hide yes)
			)
		)
		(pin "1"
		)
		(pin "2"
		)
		(pin "3"
		)
		(pin "4"
		)
		(instances
			(project "thunderbolt-gpu-adapter"
				(path ""
					(reference "U9")
					(unit 1)
				)
			)
		)
	)
)
